FILE_TYPE = MACRO_DRAWING;
SET COLOR_WIRE YELLOW;
SET COLOR_PROP ORANGE;
SET COLOR_DOT WHITE;
SET COLOR_ARC YELLOW;
SET COLOR_BODY GREEN;
SET COLOR_NOTE PURPLE;
SET PROP_DISPLAY VALUE;
SET PAGE_NUMBER P12;
FORCEADD GENOA_SP5..3
(-4775 3575);
FORCEPROP 1 LAST LOCATION U25
J 0
(-5420 6406);
DISPLAY 0.489362 (-5420 6406);
PAINT SKYBLUE (-5420 6406);
FORCEPROP 0 LAST $SEC 3
J 0
(-5400 6550);
DISPLAY 0.680851 (-5400 6550);
PAINT MONO (-5400 6550);
DISPLAY INVISIBLE (-5400 6550);
FORCEPROP 0 LAST CDS_SEC 3
J 0
(-5400 6550);
DISPLAY 1.021277 (-5400 6550);
DISPLAY INVISIBLE (-5400 6550);
FORCEPROP 0 LASTPIN (-5575 2950) $PN BC57
J 2
(-5585 2960);
DISPLAY 0.489362 (-5585 2960);
PAINT MONO (-5585 2960);
FORCEPROP 0 LASTPIN (-5575 2900) $PN BD56
J 2
(-5585 2910);
DISPLAY 0.489362 (-5585 2910);
PAINT MONO (-5585 2910);
FORCEPROP 0 LASTPIN (-5575 1800) $PN BF56
J 2
(-5585 1810);
DISPLAY 0.489362 (-5585 1810);
PAINT MONO (-5585 1810);
FORCEPROP 0 LASTPIN (-5575 1750) $PN BG57
J 2
(-5585 1760);
DISPLAY 0.489362 (-5585 1760);
PAINT MONO (-5585 1760);
FORCEPROP 0 LASTPIN (-5575 2100) $PN AT55
J 2
(-5585 2110);
DISPLAY 0.489362 (-5585 2110);
PAINT MONO (-5585 2110);
FORCEPROP 0 LASTPIN (-5575 2000) $PN AU55
J 2
(-5585 2010);
DISPLAY 0.489362 (-5585 2010);
PAINT MONO (-5585 2010);
FORCEPROP 0 LASTPIN (-5575 2800) $PN AV56
J 2
(-5585 2810);
DISPLAY 0.489362 (-5585 2810);
PAINT MONO (-5585 2810);
FORCEPROP 0 LASTPIN (-5575 2750) $PN AW55
J 2
(-5585 2760);
DISPLAY 0.489362 (-5585 2760);
PAINT MONO (-5585 2760);
FORCEPROP 0 LASTPIN (-5575 2650) $PN BN55
J 2
(-5585 2660);
DISPLAY 0.489362 (-5585 2660);
PAINT MONO (-5585 2660);
FORCEPROP 0 LASTPIN (-5575 1650) $PN AU57
J 2
(-5585 1660);
DISPLAY 0.489362 (-5585 1660);
PAINT MONO (-5585 1660);
FORCEPROP 0 LASTPIN (-5575 1600) $PN AV55
J 2
(-5585 1610);
DISPLAY 0.489362 (-5585 1610);
PAINT MONO (-5585 1610);
FORCEPROP 0 LASTPIN (-5575 1500) $PN BP55
J 2
(-5585 1510);
DISPLAY 0.489362 (-5585 1510);
PAINT MONO (-5585 1510);
FORCEPROP 0 LASTPIN (-5575 3800) $PN AW57
J 2
(-5585 3810);
DISPLAY 0.489362 (-5585 3810);
PAINT MONO (-5585 3810);
FORCEPROP 0 LASTPIN (-5575 3750) $PN AY56
J 2
(-5585 3760);
DISPLAY 0.489362 (-5585 3760);
PAINT MONO (-5585 3760);
FORCEPROP 0 LASTPIN (-5575 3700) $PN AY55
J 2
(-5585 3710);
DISPLAY 0.489362 (-5585 3710);
PAINT MONO (-5585 3710);
FORCEPROP 0 LASTPIN (-5575 3650) $PN BA55
J 2
(-5585 3660);
DISPLAY 0.489362 (-5585 3660);
PAINT MONO (-5585 3660);
FORCEPROP 0 LASTPIN (-5575 3600) $PN BA57
J 2
(-5585 3610);
DISPLAY 0.489362 (-5585 3610);
PAINT MONO (-5585 3610);
FORCEPROP 0 LASTPIN (-5575 3550) $PN BB56
J 2
(-5585 3560);
DISPLAY 0.489362 (-5585 3560);
PAINT MONO (-5585 3560);
FORCEPROP 0 LASTPIN (-5575 3500) $PN BB55
J 2
(-5585 3510);
DISPLAY 0.489362 (-5585 3510);
PAINT MONO (-5585 3510);
FORCEPROP 0 LASTPIN (-3975 2350) $PN AJ57
J 0
(-3965 2360);
DISPLAY 0.489362 (-3965 2360);
PAINT MONO (-3965 2360);
FORCEPROP 0 LASTPIN (-3975 2300) $PN AK55
J 0
(-3965 2310);
DISPLAY 0.489362 (-3965 2310);
PAINT MONO (-3965 2310);
FORCEPROP 0 LASTPIN (-3975 2250) $PN AK56
J 0
(-3965 2260);
DISPLAY 0.489362 (-3965 2260);
PAINT MONO (-3965 2260);
FORCEPROP 0 LASTPIN (-3975 2200) $PN AL55
J 0
(-3965 2210);
DISPLAY 0.489362 (-3965 2210);
PAINT MONO (-3965 2210);
FORCEPROP 0 LASTPIN (-3975 2150) $PN AN57
J 0
(-3965 2160);
DISPLAY 0.489362 (-3965 2160);
PAINT MONO (-3965 2160);
FORCEPROP 0 LASTPIN (-3975 2100) $PN AP55
J 0
(-3965 2110);
DISPLAY 0.489362 (-3965 2110);
PAINT MONO (-3965 2110);
FORCEPROP 0 LASTPIN (-3975 2050) $PN AP56
J 0
(-3965 2060);
DISPLAY 0.489362 (-3965 2060);
PAINT MONO (-3965 2060);
FORCEPROP 0 LASTPIN (-3975 2000) $PN AR55
J 0
(-3965 2010);
DISPLAY 0.489362 (-3965 2010);
PAINT MONO (-3965 2010);
FORCEPROP 0 LASTPIN (-3975 5950) $PN E57
J 0
(-3965 5960);
DISPLAY 0.489362 (-3965 5960);
PAINT MONO (-3965 5960);
FORCEPROP 0 LASTPIN (-3975 5900) $PN F55
J 0
(-3965 5910);
DISPLAY 0.489362 (-3965 5910);
PAINT MONO (-3965 5910);
FORCEPROP 0 LASTPIN (-3975 5850) $PN F56
J 0
(-3965 5860);
DISPLAY 0.489362 (-3965 5860);
PAINT MONO (-3965 5860);
FORCEPROP 0 LASTPIN (-3975 5800) $PN G55
J 0
(-3965 5810);
DISPLAY 0.489362 (-3965 5810);
PAINT MONO (-3965 5810);
FORCEPROP 0 LASTPIN (-3975 5750) $PN J57
J 0
(-3965 5760);
DISPLAY 0.489362 (-3965 5760);
PAINT MONO (-3965 5760);
FORCEPROP 0 LASTPIN (-3975 5700) $PN K55
J 0
(-3965 5710);
DISPLAY 0.489362 (-3965 5710);
PAINT MONO (-3965 5710);
FORCEPROP 0 LASTPIN (-3975 5650) $PN K56
J 0
(-3965 5660);
DISPLAY 0.489362 (-3965 5660);
PAINT MONO (-3965 5660);
FORCEPROP 0 LASTPIN (-3975 5600) $PN L55
J 0
(-3965 5610);
DISPLAY 0.489362 (-3965 5610);
PAINT MONO (-3965 5610);
FORCEPROP 0 LASTPIN (-3975 5500) $PN L57
J 0
(-3965 5510);
DISPLAY 0.489362 (-3965 5510);
PAINT MONO (-3965 5510);
FORCEPROP 0 LASTPIN (-3975 5450) $PN M55
J 0
(-3965 5460);
DISPLAY 0.489362 (-3965 5460);
PAINT MONO (-3965 5460);
FORCEPROP 0 LASTPIN (-3975 5400) $PN M56
J 0
(-3965 5410);
DISPLAY 0.489362 (-3965 5410);
PAINT MONO (-3965 5410);
FORCEPROP 0 LASTPIN (-3975 5350) $PN N55
J 0
(-3965 5360);
DISPLAY 0.489362 (-3965 5360);
PAINT MONO (-3965 5360);
FORCEPROP 0 LASTPIN (-3975 5300) $PN R57
J 0
(-3965 5310);
DISPLAY 0.489362 (-3965 5310);
PAINT MONO (-3965 5310);
FORCEPROP 0 LASTPIN (-3975 5250) $PN T55
J 0
(-3965 5260);
DISPLAY 0.489362 (-3965 5260);
PAINT MONO (-3965 5260);
FORCEPROP 0 LASTPIN (-3975 5200) $PN T56
J 0
(-3965 5210);
DISPLAY 0.489362 (-3965 5210);
PAINT MONO (-3965 5210);
FORCEPROP 0 LASTPIN (-3975 5150) $PN U55
J 0
(-3965 5160);
DISPLAY 0.489362 (-3965 5160);
PAINT MONO (-3965 5160);
FORCEPROP 0 LASTPIN (-3975 5050) $PN U57
J 0
(-3965 5060);
DISPLAY 0.489362 (-3965 5060);
PAINT MONO (-3965 5060);
FORCEPROP 0 LASTPIN (-3975 5000) $PN V55
J 0
(-3965 5010);
DISPLAY 0.489362 (-3965 5010);
PAINT MONO (-3965 5010);
FORCEPROP 0 LASTPIN (-3975 4950) $PN V56
J 0
(-3965 4960);
DISPLAY 0.489362 (-3965 4960);
PAINT MONO (-3965 4960);
FORCEPROP 0 LASTPIN (-3975 4900) $PN W55
J 0
(-3965 4910);
DISPLAY 0.489362 (-3965 4910);
PAINT MONO (-3965 4910);
FORCEPROP 0 LASTPIN (-3975 4850) $PN AA57
J 0
(-3965 4860);
DISPLAY 0.489362 (-3965 4860);
PAINT MONO (-3965 4860);
FORCEPROP 0 LASTPIN (-3975 4800) $PN AB55
J 0
(-3965 4810);
DISPLAY 0.489362 (-3965 4810);
PAINT MONO (-3965 4810);
FORCEPROP 0 LASTPIN (-3975 4750) $PN AB56
J 0
(-3965 4760);
DISPLAY 0.489362 (-3965 4760);
PAINT MONO (-3965 4760);
FORCEPROP 0 LASTPIN (-3975 4700) $PN AC55
J 0
(-3965 4710);
DISPLAY 0.489362 (-3965 4710);
PAINT MONO (-3965 4710);
FORCEPROP 0 LASTPIN (-3975 4600) $PN AC57
J 0
(-3965 4610);
DISPLAY 0.489362 (-3965 4610);
PAINT MONO (-3965 4610);
FORCEPROP 0 LASTPIN (-3975 4550) $PN AD55
J 0
(-3965 4560);
DISPLAY 0.489362 (-3965 4560);
PAINT MONO (-3965 4560);
FORCEPROP 0 LASTPIN (-3975 4500) $PN AD56
J 0
(-3965 4510);
DISPLAY 0.489362 (-3965 4510);
PAINT MONO (-3965 4510);
FORCEPROP 0 LASTPIN (-3975 4450) $PN AE55
J 0
(-3965 4460);
DISPLAY 0.489362 (-3965 4460);
PAINT MONO (-3965 4460);
FORCEPROP 0 LASTPIN (-3975 4400) $PN AG57
J 0
(-3965 4410);
DISPLAY 0.489362 (-3965 4410);
PAINT MONO (-3965 4410);
FORCEPROP 0 LASTPIN (-3975 4350) $PN AH55
J 0
(-3965 4360);
DISPLAY 0.489362 (-3965 4360);
PAINT MONO (-3965 4360);
FORCEPROP 0 LASTPIN (-3975 4300) $PN AH56
J 0
(-3965 4310);
DISPLAY 0.489362 (-3965 4310);
PAINT MONO (-3965 4310);
FORCEPROP 0 LASTPIN (-3975 4250) $PN AJ55
J 0
(-3965 4260);
DISPLAY 0.489362 (-3965 4260);
PAINT MONO (-3965 4260);
FORCEPROP 0 LASTPIN (-5575 5950) $PN G57
J 2
(-5585 5960);
DISPLAY 0.489362 (-5585 5960);
PAINT MONO (-5585 5960);
FORCEPROP 0 LASTPIN (-5575 5850) $PN N57
J 2
(-5585 5860);
DISPLAY 0.489362 (-5585 5860);
PAINT MONO (-5585 5860);
FORCEPROP 0 LASTPIN (-5575 5750) $PN W57
J 2
(-5585 5760);
DISPLAY 0.489362 (-5585 5760);
PAINT MONO (-5585 5760);
FORCEPROP 0 LASTPIN (-5575 5650) $PN AE57
J 2
(-5585 5660);
DISPLAY 0.489362 (-5585 5660);
PAINT MONO (-5585 5660);
FORCEPROP 0 LASTPIN (-5575 5550) $PN AL57
J 2
(-5585 5560);
DISPLAY 0.489362 (-5585 5560);
PAINT MONO (-5585 5560);
FORCEPROP 0 LASTPIN (-5575 5450) $PN J55
J 2
(-5585 5460);
DISPLAY 0.489362 (-5585 5460);
PAINT MONO (-5585 5460);
FORCEPROP 0 LASTPIN (-5575 5350) $PN R55
J 2
(-5585 5360);
DISPLAY 0.489362 (-5585 5360);
PAINT MONO (-5585 5360);
FORCEPROP 0 LASTPIN (-5575 5250) $PN AA55
J 2
(-5585 5260);
DISPLAY 0.489362 (-5585 5260);
PAINT MONO (-5585 5260);
FORCEPROP 0 LASTPIN (-5575 5150) $PN AG55
J 2
(-5585 5160);
DISPLAY 0.489362 (-5585 5160);
PAINT MONO (-5585 5160);
FORCEPROP 0 LASTPIN (-5575 5050) $PN AN55
J 2
(-5585 5060);
DISPLAY 0.489362 (-5585 5060);
PAINT MONO (-5585 5060);
FORCEPROP 0 LASTPIN (-5575 5900) $PN H56
J 2
(-5585 5910);
DISPLAY 0.489362 (-5585 5910);
PAINT MONO (-5585 5910);
FORCEPROP 0 LASTPIN (-5575 5800) $PN P56
J 2
(-5585 5810);
DISPLAY 0.489362 (-5585 5810);
PAINT MONO (-5585 5810);
FORCEPROP 0 LASTPIN (-5575 5700) $PN Y56
J 2
(-5585 5710);
DISPLAY 0.489362 (-5585 5710);
PAINT MONO (-5585 5710);
FORCEPROP 0 LASTPIN (-5575 5600) $PN AF56
J 2
(-5585 5610);
DISPLAY 0.489362 (-5585 5610);
PAINT MONO (-5585 5610);
FORCEPROP 0 LASTPIN (-5575 5500) $PN AM56
J 2
(-5585 5510);
DISPLAY 0.489362 (-5585 5510);
PAINT MONO (-5585 5510);
FORCEPROP 0 LASTPIN (-5575 5400) $PN H55
J 2
(-5585 5410);
DISPLAY 0.489362 (-5585 5410);
PAINT MONO (-5585 5410);
FORCEPROP 0 LASTPIN (-5575 5300) $PN P55
J 2
(-5585 5310);
DISPLAY 0.489362 (-5585 5310);
PAINT MONO (-5585 5310);
FORCEPROP 0 LASTPIN (-5575 5200) $PN Y55
J 2
(-5585 5210);
DISPLAY 0.489362 (-5585 5210);
PAINT MONO (-5585 5210);
FORCEPROP 0 LASTPIN (-5575 5100) $PN AF55
J 2
(-5585 5110);
DISPLAY 0.489362 (-5585 5110);
PAINT MONO (-5585 5110);
FORCEPROP 0 LASTPIN (-5575 5000) $PN AM55
J 2
(-5585 5010);
DISPLAY 0.489362 (-5585 5010);
PAINT MONO (-5585 5010);
FORCEPROP 0 LASTPIN (-5575 2550) $PN BC55
J 2
(-5585 2560);
DISPLAY 0.489362 (-5585 2560);
PAINT MONO (-5585 2560);
FORCEPROP 0 LASTPIN (-5575 2450) $PN BM55
J 2
(-5585 2460);
DISPLAY 0.489362 (-5585 2460);
PAINT MONO (-5585 2460);
FORCEPROP 0 LASTPIN (-5575 2400) $PN BN57
J 2
(-5585 2410);
DISPLAY 0.489362 (-5585 2410);
PAINT MONO (-5585 2410);
FORCEPROP 0 LASTPIN (-5575 2300) $PN BP56
J 2
(-5585 2310);
DISPLAY 0.489362 (-5585 2310);
PAINT MONO (-5585 2310);
FORCEPROP 0 LASTPIN (-5575 1400) $PN BL55
J 2
(-5585 1410);
DISPLAY 0.489362 (-5585 1410);
PAINT MONO (-5585 1410);
FORCEPROP 0 LASTPIN (-5575 1350) $PN BM56
J 2
(-5585 1360);
DISPLAY 0.489362 (-5585 1360);
PAINT MONO (-5585 1360);
FORCEPROP 0 LASTPIN (-5575 1250) $PN BR57
J 2
(-5585 1260);
DISPLAY 0.489362 (-5585 1260);
PAINT MONO (-5585 1260);
FORCEPROP 0 LASTPIN (-5575 3400) $PN BG55
J 2
(-5585 3410);
DISPLAY 0.489362 (-5585 3410);
PAINT MONO (-5585 3410);
FORCEPROP 0 LASTPIN (-5575 3350) $PN BH55
J 2
(-5585 3360);
DISPLAY 0.489362 (-5585 3360);
PAINT MONO (-5585 3360);
FORCEPROP 0 LASTPIN (-5575 3300) $PN BH56
J 2
(-5585 3310);
DISPLAY 0.489362 (-5585 3310);
PAINT MONO (-5585 3310);
FORCEPROP 0 LASTPIN (-5575 3250) $PN BJ57
J 2
(-5585 3260);
DISPLAY 0.489362 (-5585 3260);
PAINT MONO (-5585 3260);
FORCEPROP 0 LASTPIN (-5575 3200) $PN BJ55
J 2
(-5585 3210);
DISPLAY 0.489362 (-5585 3210);
PAINT MONO (-5585 3210);
FORCEPROP 0 LASTPIN (-5575 3150) $PN BK55
J 2
(-5585 3160);
DISPLAY 0.489362 (-5585 3160);
PAINT MONO (-5585 3160);
FORCEPROP 0 LASTPIN (-5575 3100) $PN BK56
J 2
(-5585 3110);
DISPLAY 0.489362 (-5585 3110);
PAINT MONO (-5585 3110);
FORCEPROP 0 LASTPIN (-3975 1900) $PN BY56
J 0
(-3965 1910);
DISPLAY 0.489362 (-3965 1910);
PAINT MONO (-3965 1910);
FORCEPROP 0 LASTPIN (-3975 1850) $PN CA55
J 0
(-3965 1860);
DISPLAY 0.489362 (-3965 1860);
PAINT MONO (-3965 1860);
FORCEPROP 0 LASTPIN (-3975 1800) $PN CA57
J 0
(-3965 1810);
DISPLAY 0.489362 (-3965 1810);
PAINT MONO (-3965 1810);
FORCEPROP 0 LASTPIN (-3975 1750) $PN CB55
J 0
(-3965 1760);
DISPLAY 0.489362 (-3965 1760);
PAINT MONO (-3965 1760);
FORCEPROP 0 LASTPIN (-3975 1700) $PN BT56
J 0
(-3965 1710);
DISPLAY 0.489362 (-3965 1710);
PAINT MONO (-3965 1710);
FORCEPROP 0 LASTPIN (-3975 1650) $PN BU55
J 0
(-3965 1660);
DISPLAY 0.489362 (-3965 1660);
PAINT MONO (-3965 1660);
FORCEPROP 0 LASTPIN (-3975 1600) $PN BU57
J 0
(-3965 1610);
DISPLAY 0.489362 (-3965 1610);
PAINT MONO (-3965 1610);
FORCEPROP 0 LASTPIN (-3975 1550) $PN BV55
J 0
(-3965 1560);
DISPLAY 0.489362 (-3965 1560);
PAINT MONO (-3965 1560);
FORCEPROP 0 LASTPIN (-3975 4150) $PN CB56
J 0
(-3965 4160);
DISPLAY 0.489362 (-3965 4160);
PAINT MONO (-3965 4160);
FORCEPROP 0 LASTPIN (-3975 4100) $PN CC55
J 0
(-3965 4110);
DISPLAY 0.489362 (-3965 4110);
PAINT MONO (-3965 4110);
FORCEPROP 0 LASTPIN (-3975 4050) $PN CC57
J 0
(-3965 4060);
DISPLAY 0.489362 (-3965 4060);
PAINT MONO (-3965 4060);
FORCEPROP 0 LASTPIN (-3975 4000) $PN CD55
J 0
(-3965 4010);
DISPLAY 0.489362 (-3965 4010);
PAINT MONO (-3965 4010);
FORCEPROP 0 LASTPIN (-3975 3950) $PN CF56
J 0
(-3965 3960);
DISPLAY 0.489362 (-3965 3960);
PAINT MONO (-3965 3960);
FORCEPROP 0 LASTPIN (-3975 3900) $PN CG55
J 0
(-3965 3910);
DISPLAY 0.489362 (-3965 3910);
PAINT MONO (-3965 3910);
FORCEPROP 0 LASTPIN (-3975 3850) $PN CG57
J 0
(-3965 3860);
DISPLAY 0.489362 (-3965 3860);
PAINT MONO (-3965 3860);
FORCEPROP 0 LASTPIN (-3975 3800) $PN CH55
J 0
(-3965 3810);
DISPLAY 0.489362 (-3965 3810);
PAINT MONO (-3965 3810);
FORCEPROP 0 LASTPIN (-3975 3700) $PN CH56
J 0
(-3965 3710);
DISPLAY 0.489362 (-3965 3710);
PAINT MONO (-3965 3710);
FORCEPROP 0 LASTPIN (-3975 3650) $PN CJ55
J 0
(-3965 3660);
DISPLAY 0.489362 (-3965 3660);
PAINT MONO (-3965 3660);
FORCEPROP 0 LASTPIN (-3975 3600) $PN CJ57
J 0
(-3965 3610);
DISPLAY 0.489362 (-3965 3610);
PAINT MONO (-3965 3610);
FORCEPROP 0 LASTPIN (-3975 3550) $PN CK55
J 0
(-3965 3560);
DISPLAY 0.489362 (-3965 3560);
PAINT MONO (-3965 3560);
FORCEPROP 0 LASTPIN (-3975 3500) $PN CM56
J 0
(-3965 3510);
DISPLAY 0.489362 (-3965 3510);
PAINT MONO (-3965 3510);
FORCEPROP 0 LASTPIN (-3975 3450) $PN CN55
J 0
(-3965 3460);
DISPLAY 0.489362 (-3965 3460);
PAINT MONO (-3965 3460);
FORCEPROP 0 LASTPIN (-3975 3400) $PN CN57
J 0
(-3965 3410);
DISPLAY 0.489362 (-3965 3410);
PAINT MONO (-3965 3410);
FORCEPROP 0 LASTPIN (-3975 3350) $PN CP55
J 0
(-3965 3360);
DISPLAY 0.489362 (-3965 3360);
PAINT MONO (-3965 3360);
FORCEPROP 0 LASTPIN (-3975 3250) $PN CP56
J 0
(-3965 3260);
DISPLAY 0.489362 (-3965 3260);
PAINT MONO (-3965 3260);
FORCEPROP 0 LASTPIN (-3975 3200) $PN CR55
J 0
(-3965 3210);
DISPLAY 0.489362 (-3965 3210);
PAINT MONO (-3965 3210);
FORCEPROP 0 LASTPIN (-3975 3150) $PN CR57
J 0
(-3965 3160);
DISPLAY 0.489362 (-3965 3160);
PAINT MONO (-3965 3160);
FORCEPROP 0 LASTPIN (-3975 3100) $PN CT55
J 0
(-3965 3110);
DISPLAY 0.489362 (-3965 3110);
PAINT MONO (-3965 3110);
FORCEPROP 0 LASTPIN (-3975 3050) $PN CV56
J 0
(-3965 3060);
DISPLAY 0.489362 (-3965 3060);
PAINT MONO (-3965 3060);
FORCEPROP 0 LASTPIN (-3975 3000) $PN CW55
J 0
(-3965 3010);
DISPLAY 0.489362 (-3965 3010);
PAINT MONO (-3965 3010);
FORCEPROP 0 LASTPIN (-3975 2950) $PN CW57
J 0
(-3965 2960);
DISPLAY 0.489362 (-3965 2960);
PAINT MONO (-3965 2960);
FORCEPROP 0 LASTPIN (-3975 2900) $PN CY55
J 0
(-3965 2910);
DISPLAY 0.489362 (-3965 2910);
PAINT MONO (-3965 2910);
FORCEPROP 0 LASTPIN (-3975 2800) $PN CY56
J 0
(-3965 2810);
DISPLAY 0.489362 (-3965 2810);
PAINT MONO (-3965 2810);
FORCEPROP 0 LASTPIN (-3975 2750) $PN DA55
J 0
(-3965 2760);
DISPLAY 0.489362 (-3965 2760);
PAINT MONO (-3965 2760);
FORCEPROP 0 LASTPIN (-3975 2700) $PN DA57
J 0
(-3965 2710);
DISPLAY 0.489362 (-3965 2710);
PAINT MONO (-3965 2710);
FORCEPROP 0 LASTPIN (-3975 2650) $PN DB55
J 0
(-3965 2660);
DISPLAY 0.489362 (-3965 2660);
PAINT MONO (-3965 2660);
FORCEPROP 0 LASTPIN (-3975 2600) $PN DD56
J 0
(-3965 2610);
DISPLAY 0.489362 (-3965 2610);
PAINT MONO (-3965 2610);
FORCEPROP 0 LASTPIN (-3975 2550) $PN DE55
J 0
(-3965 2560);
DISPLAY 0.489362 (-3965 2560);
PAINT MONO (-3965 2560);
FORCEPROP 0 LASTPIN (-3975 2500) $PN DE57
J 0
(-3965 2510);
DISPLAY 0.489362 (-3965 2510);
PAINT MONO (-3965 2510);
FORCEPROP 0 LASTPIN (-3975 2450) $PN DF55
J 0
(-3965 2460);
DISPLAY 0.489362 (-3965 2460);
PAINT MONO (-3965 2460);
FORCEPROP 0 LASTPIN (-5575 4900) $PN CD56
J 2
(-5585 4910);
DISPLAY 0.489362 (-5585 4910);
PAINT MONO (-5585 4910);
FORCEPROP 0 LASTPIN (-5575 4800) $PN CK56
J 2
(-5585 4810);
DISPLAY 0.489362 (-5585 4810);
PAINT MONO (-5585 4810);
FORCEPROP 0 LASTPIN (-5575 4700) $PN CT56
J 2
(-5585 4710);
DISPLAY 0.489362 (-5585 4710);
PAINT MONO (-5585 4710);
FORCEPROP 0 LASTPIN (-5575 4600) $PN DB56
J 2
(-5585 4610);
DISPLAY 0.489362 (-5585 4610);
PAINT MONO (-5585 4610);
FORCEPROP 0 LASTPIN (-5575 4500) $PN BY55
J 2
(-5585 4510);
DISPLAY 0.489362 (-5585 4510);
PAINT MONO (-5585 4510);
FORCEPROP 0 LASTPIN (-5575 4400) $PN CF55
J 2
(-5585 4410);
DISPLAY 0.489362 (-5585 4410);
PAINT MONO (-5585 4410);
FORCEPROP 0 LASTPIN (-5575 4300) $PN CM55
J 2
(-5585 4310);
DISPLAY 0.489362 (-5585 4310);
PAINT MONO (-5585 4310);
FORCEPROP 0 LASTPIN (-5575 4200) $PN CV55
J 2
(-5585 4210);
DISPLAY 0.489362 (-5585 4210);
PAINT MONO (-5585 4210);
FORCEPROP 0 LASTPIN (-5575 4100) $PN DD55
J 2
(-5585 4110);
DISPLAY 0.489362 (-5585 4110);
PAINT MONO (-5585 4110);
FORCEPROP 0 LASTPIN (-5575 4000) $PN BV56
J 2
(-5585 4010);
DISPLAY 0.489362 (-5585 4010);
PAINT MONO (-5585 4010);
FORCEPROP 0 LASTPIN (-5575 4850) $PN CE57
J 2
(-5585 4860);
DISPLAY 0.489362 (-5585 4860);
PAINT MONO (-5585 4860);
FORCEPROP 0 LASTPIN (-5575 4750) $PN CL57
J 2
(-5585 4760);
DISPLAY 0.489362 (-5585 4760);
PAINT MONO (-5585 4760);
FORCEPROP 0 LASTPIN (-5575 4650) $PN CU57
J 2
(-5585 4660);
DISPLAY 0.489362 (-5585 4660);
PAINT MONO (-5585 4660);
FORCEPROP 0 LASTPIN (-5575 4550) $PN DC57
J 2
(-5585 4560);
DISPLAY 0.489362 (-5585 4560);
PAINT MONO (-5585 4560);
FORCEPROP 0 LASTPIN (-5575 4450) $PN BW55
J 2
(-5585 4460);
DISPLAY 0.489362 (-5585 4460);
PAINT MONO (-5585 4460);
FORCEPROP 0 LASTPIN (-5575 4350) $PN CE55
J 2
(-5585 4360);
DISPLAY 0.489362 (-5585 4360);
PAINT MONO (-5585 4360);
FORCEPROP 0 LASTPIN (-5575 4250) $PN CL55
J 2
(-5585 4260);
DISPLAY 0.489362 (-5585 4260);
PAINT MONO (-5585 4260);
FORCEPROP 0 LASTPIN (-5575 4150) $PN CU55
J 2
(-5585 4160);
DISPLAY 0.489362 (-5585 4160);
PAINT MONO (-5585 4160);
FORCEPROP 0 LASTPIN (-5575 4050) $PN DC55
J 2
(-5585 4060);
DISPLAY 0.489362 (-5585 4060);
PAINT MONO (-5585 4060);
FORCEPROP 0 LASTPIN (-5575 3950) $PN BW57
J 2
(-5585 3960);
DISPLAY 0.489362 (-5585 3960);
PAINT MONO (-5585 3960);
FORCEPROP 0 LASTPIN (-5575 2200) $PN BL57
J 2
(-5585 2210);
DISPLAY 0.489362 (-5585 2210);
PAINT MONO (-5585 2210);
FORCEPROP 0 LASTPIN (-5575 1150) $PN BF55
J 2
(-5585 1160);
DISPLAY 0.489362 (-5585 1160);
PAINT MONO (-5585 1160);
FORCEPROP 2 LAST PART_TYPE SMLF
J 0
(-5400 6500);
DISPLAY 1.021277 (-5400 6500);
FORCEPROP 1 LAST MATERIAL IO
J 0
(-5420 6132);
DISPLAY 0.489362 (-5420 6132);
PAINT SKYBLUE (-5420 6132);
FORCEPROP 2 LAST VALUE SOCKET6096_13568-001
J 0
(-5400 6450);
DISPLAY 0.489362 (-5400 6450);
PAINT SKYBLUE (-5400 6450);
FORCEPROP 1 LAST PART_NUMBER DGA^6000030
J 0
(-5420 6259);
DISPLAY 0.489362 (-5420 6259);
PAINT SKYBLUE (-5420 6259);
FORCEPROP 2 LAST CDS_LIB pure_quanta
J 0
(-4775 3575);
DISPLAY INVISIBLE (-4775 3575);
FORCEPROP 1 LAST CDS_LMAN_SYM_OUTLINE -650,2525,650,-2525
J 0
(-4775 3575);
DISPLAY 0.468085 (-4775 3575);
PAINT GREEN (-4775 3575);
DISPLAY INVISIBLE (-4775 3575);
FORCEPROP 1 LAST NEEDS_NO_SIZE TRUE
J 0
(-4775 3575);
DISPLAY 0.723404 (-4775 3575);
PAINT GREEN (-4775 3575);
DISPLAY INVISIBLE (-4775 3575);
FORCEPROP 1 LAST PATH I159
J 0
(-4775 3575);
DISPLAY 0.723404 (-4775 3575);
PAINT GREEN (-4775 3575);
DISPLAY INVISIBLE (-4775 3575);
FORCEADD OFFPAGE..3
(-2775 5975);
FORCEPROP 2 LAST $XR0 87 
J 0
(-2561 5975);
DISPLAY 0.638298 (-2561 5975);
PAINT MONO (-2561 5975);
FORCEPROP 2 LAST PATH I160
J 0
(-2550 6025);
DISPLAY 1.021277 (-2550 6025);
DISPLAY INVISIBLE (-2550 6025);
FORCEPROP 1 LAST COMMENT_BODY TRUE
J 0
(-2825 5875);
DISPLAY 0.872340 (-2825 5875);
PAINT GREEN (-2825 5875);
DISPLAY INVISIBLE (-2825 5875);
FORCEPROP 1 LAST OFFPAGE TRUE
J 0
(-2450 5850);
DISPLAY 0.872340 (-2450 5850);
PAINT GREEN (-2450 5850);
DISPLAY INVISIBLE (-2450 5850);
FORCEPROP 2 LAST CDS_LIB mstr_standard
J 0
(-2775 5975);
DISPLAY 0.723404 (-2775 5975);
PAINT MONO (-2775 5975);
DISPLAY INVISIBLE (-2775 5975);
FORCEADD OFFPAGE..3
(-2775 4175);
FORCEPROP 2 LAST $XR0 87 
J 0
(-2561 4175);
DISPLAY 0.638298 (-2561 4175);
PAINT MONO (-2561 4175);
FORCEPROP 2 LAST PATH I161
J 0
(-2550 4225);
DISPLAY 1.021277 (-2550 4225);
DISPLAY INVISIBLE (-2550 4225);
FORCEPROP 1 LAST COMMENT_BODY TRUE
J 0
(-2825 4075);
DISPLAY 0.872340 (-2825 4075);
PAINT GREEN (-2825 4075);
DISPLAY INVISIBLE (-2825 4075);
FORCEPROP 1 LAST OFFPAGE TRUE
J 0
(-2450 4050);
DISPLAY 0.872340 (-2450 4050);
PAINT GREEN (-2450 4050);
DISPLAY INVISIBLE (-2450 4050);
FORCEPROP 2 LAST CDS_LIB mstr_standard
J 0
(-2775 4175);
DISPLAY 0.723404 (-2775 4175);
PAINT MONO (-2775 4175);
DISPLAY INVISIBLE (-2775 4175);
FORCEADD TAP..1
(-3500 5900);
FORCEPROP 3 LASTPIN (-3550 5900) SIG_NAME M_C_CPU0_SA_DQ<1>
J 0
(-3540 5910);
DISPLAY 0.659574 (-3540 5910);
PAINT MONO (-3540 5910);
DISPLAY INVISIBLE (-3540 5910);
FORCEPROP 1 LASTPIN (-3550 5900) BN 1
J 0
(-3562 5908);
DISPLAY 0.489362 (-3562 5908);
PAINT GREEN (-3562 5908);
FORCEPROP 2 LAST CDS_LIB mstr_standard
J 0
(-3500 5900);
DISPLAY 0.723404 (-3500 5900);
PAINT MONO (-3500 5900);
DISPLAY INVISIBLE (-3500 5900);
FORCEPROP 1 LAST BODY_TYPE PLUMBING
J 0
(-3500 5950);
DISPLAY 0.872340 (-3500 5950);
PAINT GREEN (-3500 5950);
DISPLAY INVISIBLE (-3500 5950);
FORCEPROP 1 LAST HDL_TAP TRUE
J 0
(-3175 5775);
DISPLAY 0.872340 (-3175 5775);
DISPLAY INVISIBLE (-3175 5775);
FORCEPROP 1 LAST PATH I162
J 0
(-3502 5900);
DISPLAY 0.872340 (-3502 5900);
PAINT GREEN (-3502 5900);
DISPLAY INVISIBLE (-3502 5900);
FORCEADD TAP..1
(-3500 5950);
FORCEPROP 3 LASTPIN (-3550 5950) SIG_NAME M_C_CPU0_SA_DQ<0>
J 0
(-3540 5960);
DISPLAY 0.659574 (-3540 5960);
PAINT MONO (-3540 5960);
DISPLAY INVISIBLE (-3540 5960);
FORCEPROP 1 LASTPIN (-3550 5950) BN 0
J 0
(-3562 5958);
DISPLAY 0.489362 (-3562 5958);
PAINT GREEN (-3562 5958);
FORCEPROP 2 LAST CDS_LIB mstr_standard
J 0
(-3500 5950);
DISPLAY 0.723404 (-3500 5950);
PAINT MONO (-3500 5950);
DISPLAY INVISIBLE (-3500 5950);
FORCEPROP 1 LAST BODY_TYPE PLUMBING
J 0
(-3500 6000);
DISPLAY 0.872340 (-3500 6000);
PAINT GREEN (-3500 6000);
DISPLAY INVISIBLE (-3500 6000);
FORCEPROP 1 LAST HDL_TAP TRUE
J 0
(-3175 5825);
DISPLAY 0.872340 (-3175 5825);
DISPLAY INVISIBLE (-3175 5825);
FORCEPROP 1 LAST PATH I163
J 0
(-3502 5950);
DISPLAY 0.872340 (-3502 5950);
PAINT GREEN (-3502 5950);
DISPLAY INVISIBLE (-3502 5950);
FORCEADD TAP..1
(-3500 5850);
FORCEPROP 3 LASTPIN (-3550 5850) SIG_NAME M_C_CPU0_SA_DQ<2>
J 0
(-3540 5860);
DISPLAY 0.659574 (-3540 5860);
PAINT MONO (-3540 5860);
DISPLAY INVISIBLE (-3540 5860);
FORCEPROP 1 LASTPIN (-3550 5850) BN 2
J 0
(-3562 5858);
DISPLAY 0.489362 (-3562 5858);
PAINT GREEN (-3562 5858);
FORCEPROP 2 LAST CDS_LIB mstr_standard
J 0
(-3500 5850);
DISPLAY 0.723404 (-3500 5850);
PAINT MONO (-3500 5850);
DISPLAY INVISIBLE (-3500 5850);
FORCEPROP 1 LAST BODY_TYPE PLUMBING
J 0
(-3500 5900);
DISPLAY 0.872340 (-3500 5900);
PAINT GREEN (-3500 5900);
DISPLAY INVISIBLE (-3500 5900);
FORCEPROP 1 LAST HDL_TAP TRUE
J 0
(-3175 5725);
DISPLAY 0.872340 (-3175 5725);
DISPLAY INVISIBLE (-3175 5725);
FORCEPROP 1 LAST PATH I164
J 0
(-3502 5850);
DISPLAY 0.872340 (-3502 5850);
PAINT GREEN (-3502 5850);
DISPLAY INVISIBLE (-3502 5850);
FORCEADD TAP..1
(-3500 5800);
FORCEPROP 3 LASTPIN (-3550 5800) SIG_NAME M_C_CPU0_SA_DQ<3>
J 0
(-3540 5810);
DISPLAY 0.659574 (-3540 5810);
PAINT MONO (-3540 5810);
DISPLAY INVISIBLE (-3540 5810);
FORCEPROP 1 LASTPIN (-3550 5800) BN 3
J 0
(-3562 5808);
DISPLAY 0.489362 (-3562 5808);
PAINT GREEN (-3562 5808);
FORCEPROP 2 LAST CDS_LIB mstr_standard
J 0
(-3500 5800);
DISPLAY 0.723404 (-3500 5800);
PAINT MONO (-3500 5800);
DISPLAY INVISIBLE (-3500 5800);
FORCEPROP 1 LAST BODY_TYPE PLUMBING
J 0
(-3500 5850);
DISPLAY 0.872340 (-3500 5850);
PAINT GREEN (-3500 5850);
DISPLAY INVISIBLE (-3500 5850);
FORCEPROP 1 LAST HDL_TAP TRUE
J 0
(-3175 5675);
DISPLAY 0.872340 (-3175 5675);
DISPLAY INVISIBLE (-3175 5675);
FORCEPROP 1 LAST PATH I165
J 0
(-3502 5800);
DISPLAY 0.872340 (-3502 5800);
PAINT GREEN (-3502 5800);
DISPLAY INVISIBLE (-3502 5800);
FORCEADD TAP..1
(-3500 5750);
FORCEPROP 3 LASTPIN (-3550 5750) SIG_NAME M_C_CPU0_SA_DQ<4>
J 0
(-3540 5760);
DISPLAY 0.659574 (-3540 5760);
PAINT MONO (-3540 5760);
DISPLAY INVISIBLE (-3540 5760);
FORCEPROP 1 LASTPIN (-3550 5750) BN 4
J 0
(-3562 5758);
DISPLAY 0.489362 (-3562 5758);
PAINT GREEN (-3562 5758);
FORCEPROP 2 LAST CDS_LIB mstr_standard
J 0
(-3500 5750);
DISPLAY 0.723404 (-3500 5750);
PAINT MONO (-3500 5750);
DISPLAY INVISIBLE (-3500 5750);
FORCEPROP 1 LAST BODY_TYPE PLUMBING
J 0
(-3500 5800);
DISPLAY 0.872340 (-3500 5800);
PAINT GREEN (-3500 5800);
DISPLAY INVISIBLE (-3500 5800);
FORCEPROP 1 LAST HDL_TAP TRUE
J 0
(-3175 5625);
DISPLAY 0.872340 (-3175 5625);
DISPLAY INVISIBLE (-3175 5625);
FORCEPROP 1 LAST PATH I166
J 0
(-3502 5750);
DISPLAY 0.872340 (-3502 5750);
PAINT GREEN (-3502 5750);
DISPLAY INVISIBLE (-3502 5750);
FORCEADD TAP..1
(-3500 5700);
FORCEPROP 3 LASTPIN (-3550 5700) SIG_NAME M_C_CPU0_SA_DQ<5>
J 0
(-3540 5710);
DISPLAY 0.659574 (-3540 5710);
PAINT MONO (-3540 5710);
DISPLAY INVISIBLE (-3540 5710);
FORCEPROP 1 LASTPIN (-3550 5700) BN 5
J 0
(-3562 5708);
DISPLAY 0.489362 (-3562 5708);
PAINT GREEN (-3562 5708);
FORCEPROP 2 LAST CDS_LIB mstr_standard
J 0
(-3500 5700);
DISPLAY 0.723404 (-3500 5700);
PAINT MONO (-3500 5700);
DISPLAY INVISIBLE (-3500 5700);
FORCEPROP 1 LAST BODY_TYPE PLUMBING
J 0
(-3500 5750);
DISPLAY 0.872340 (-3500 5750);
PAINT GREEN (-3500 5750);
DISPLAY INVISIBLE (-3500 5750);
FORCEPROP 1 LAST HDL_TAP TRUE
J 0
(-3175 5575);
DISPLAY 0.872340 (-3175 5575);
DISPLAY INVISIBLE (-3175 5575);
FORCEPROP 1 LAST PATH I167
J 0
(-3502 5700);
DISPLAY 0.872340 (-3502 5700);
PAINT GREEN (-3502 5700);
DISPLAY INVISIBLE (-3502 5700);
FORCEADD TAP..1
(-3500 5650);
FORCEPROP 3 LASTPIN (-3550 5650) SIG_NAME M_C_CPU0_SA_DQ<6>
J 0
(-3540 5660);
DISPLAY 0.659574 (-3540 5660);
PAINT MONO (-3540 5660);
DISPLAY INVISIBLE (-3540 5660);
FORCEPROP 1 LASTPIN (-3550 5650) BN 6
J 0
(-3562 5658);
DISPLAY 0.489362 (-3562 5658);
PAINT GREEN (-3562 5658);
FORCEPROP 2 LAST CDS_LIB mstr_standard
J 0
(-3500 5650);
DISPLAY 0.723404 (-3500 5650);
PAINT MONO (-3500 5650);
DISPLAY INVISIBLE (-3500 5650);
FORCEPROP 1 LAST BODY_TYPE PLUMBING
J 0
(-3500 5700);
DISPLAY 0.872340 (-3500 5700);
PAINT GREEN (-3500 5700);
DISPLAY INVISIBLE (-3500 5700);
FORCEPROP 1 LAST HDL_TAP TRUE
J 0
(-3175 5525);
DISPLAY 0.872340 (-3175 5525);
DISPLAY INVISIBLE (-3175 5525);
FORCEPROP 1 LAST PATH I168
J 0
(-3502 5650);
DISPLAY 0.872340 (-3502 5650);
PAINT GREEN (-3502 5650);
DISPLAY INVISIBLE (-3502 5650);
FORCEADD TAP..1
(-3500 5600);
FORCEPROP 3 LASTPIN (-3550 5600) SIG_NAME M_C_CPU0_SA_DQ<7>
J 0
(-3540 5610);
DISPLAY 0.659574 (-3540 5610);
PAINT MONO (-3540 5610);
DISPLAY INVISIBLE (-3540 5610);
FORCEPROP 1 LASTPIN (-3550 5600) BN 7
J 0
(-3562 5608);
DISPLAY 0.489362 (-3562 5608);
PAINT GREEN (-3562 5608);
FORCEPROP 2 LAST CDS_LIB mstr_standard
J 0
(-3500 5600);
DISPLAY 0.723404 (-3500 5600);
PAINT MONO (-3500 5600);
DISPLAY INVISIBLE (-3500 5600);
FORCEPROP 1 LAST BODY_TYPE PLUMBING
J 0
(-3500 5650);
DISPLAY 0.872340 (-3500 5650);
PAINT GREEN (-3500 5650);
DISPLAY INVISIBLE (-3500 5650);
FORCEPROP 1 LAST HDL_TAP TRUE
J 0
(-3175 5475);
DISPLAY 0.872340 (-3175 5475);
DISPLAY INVISIBLE (-3175 5475);
FORCEPROP 1 LAST PATH I169
J 0
(-3502 5600);
DISPLAY 0.872340 (-3502 5600);
PAINT GREEN (-3502 5600);
DISPLAY INVISIBLE (-3502 5600);
FORCEADD TAP..1
(-3500 5500);
FORCEPROP 3 LASTPIN (-3550 5500) SIG_NAME M_C_CPU0_SA_DQ<8>
J 0
(-3540 5510);
DISPLAY 0.659574 (-3540 5510);
PAINT MONO (-3540 5510);
DISPLAY INVISIBLE (-3540 5510);
FORCEPROP 1 LASTPIN (-3550 5500) BN 8
J 0
(-3562 5508);
DISPLAY 0.489362 (-3562 5508);
PAINT GREEN (-3562 5508);
FORCEPROP 2 LAST CDS_LIB mstr_standard
J 0
(-3500 5500);
DISPLAY 0.723404 (-3500 5500);
PAINT MONO (-3500 5500);
DISPLAY INVISIBLE (-3500 5500);
FORCEPROP 1 LAST BODY_TYPE PLUMBING
J 0
(-3500 5550);
DISPLAY 0.872340 (-3500 5550);
PAINT GREEN (-3500 5550);
DISPLAY INVISIBLE (-3500 5550);
FORCEPROP 1 LAST HDL_TAP TRUE
J 0
(-3175 5375);
DISPLAY 0.872340 (-3175 5375);
DISPLAY INVISIBLE (-3175 5375);
FORCEPROP 1 LAST PATH I170
J 0
(-3502 5500);
DISPLAY 0.872340 (-3502 5500);
PAINT GREEN (-3502 5500);
DISPLAY INVISIBLE (-3502 5500);
FORCEADD TAP..1
(-3500 5400);
FORCEPROP 3 LASTPIN (-3550 5400) SIG_NAME M_C_CPU0_SA_DQ<10>
J 0
(-3540 5410);
DISPLAY 0.659574 (-3540 5410);
PAINT MONO (-3540 5410);
DISPLAY INVISIBLE (-3540 5410);
FORCEPROP 1 LASTPIN (-3550 5400) BN 10
J 0
(-3562 5408);
DISPLAY 0.489362 (-3562 5408);
PAINT GREEN (-3562 5408);
FORCEPROP 2 LAST CDS_LIB mstr_standard
J 0
(-3500 5400);
DISPLAY 0.723404 (-3500 5400);
PAINT MONO (-3500 5400);
DISPLAY INVISIBLE (-3500 5400);
FORCEPROP 1 LAST BODY_TYPE PLUMBING
J 0
(-3500 5450);
DISPLAY 0.872340 (-3500 5450);
PAINT GREEN (-3500 5450);
DISPLAY INVISIBLE (-3500 5450);
FORCEPROP 1 LAST HDL_TAP TRUE
J 0
(-3175 5275);
DISPLAY 0.872340 (-3175 5275);
DISPLAY INVISIBLE (-3175 5275);
FORCEPROP 1 LAST PATH I171
J 0
(-3502 5400);
DISPLAY 0.872340 (-3502 5400);
PAINT GREEN (-3502 5400);
DISPLAY INVISIBLE (-3502 5400);
FORCEADD TAP..1
(-3500 5450);
FORCEPROP 3 LASTPIN (-3550 5450) SIG_NAME M_C_CPU0_SA_DQ<9>
J 0
(-3540 5460);
DISPLAY 0.659574 (-3540 5460);
PAINT MONO (-3540 5460);
DISPLAY INVISIBLE (-3540 5460);
FORCEPROP 1 LASTPIN (-3550 5450) BN 9
J 0
(-3562 5458);
DISPLAY 0.489362 (-3562 5458);
PAINT GREEN (-3562 5458);
FORCEPROP 2 LAST CDS_LIB mstr_standard
J 0
(-3500 5450);
DISPLAY 0.723404 (-3500 5450);
PAINT MONO (-3500 5450);
DISPLAY INVISIBLE (-3500 5450);
FORCEPROP 1 LAST BODY_TYPE PLUMBING
J 0
(-3500 5500);
DISPLAY 0.872340 (-3500 5500);
PAINT GREEN (-3500 5500);
DISPLAY INVISIBLE (-3500 5500);
FORCEPROP 1 LAST HDL_TAP TRUE
J 0
(-3175 5325);
DISPLAY 0.872340 (-3175 5325);
DISPLAY INVISIBLE (-3175 5325);
FORCEPROP 1 LAST PATH I172
J 0
(-3502 5450);
DISPLAY 0.872340 (-3502 5450);
PAINT GREEN (-3502 5450);
DISPLAY INVISIBLE (-3502 5450);
FORCEADD TAP..1
(-3500 5350);
FORCEPROP 3 LASTPIN (-3550 5350) SIG_NAME M_C_CPU0_SA_DQ<11>
J 0
(-3540 5360);
DISPLAY 0.659574 (-3540 5360);
PAINT MONO (-3540 5360);
DISPLAY INVISIBLE (-3540 5360);
FORCEPROP 1 LASTPIN (-3550 5350) BN 11
J 0
(-3562 5358);
DISPLAY 0.489362 (-3562 5358);
PAINT GREEN (-3562 5358);
FORCEPROP 2 LAST CDS_LIB mstr_standard
J 0
(-3500 5350);
DISPLAY 0.723404 (-3500 5350);
PAINT MONO (-3500 5350);
DISPLAY INVISIBLE (-3500 5350);
FORCEPROP 1 LAST BODY_TYPE PLUMBING
J 0
(-3500 5400);
DISPLAY 0.872340 (-3500 5400);
PAINT GREEN (-3500 5400);
DISPLAY INVISIBLE (-3500 5400);
FORCEPROP 1 LAST HDL_TAP TRUE
J 0
(-3175 5225);
DISPLAY 0.872340 (-3175 5225);
DISPLAY INVISIBLE (-3175 5225);
FORCEPROP 1 LAST PATH I173
J 0
(-3502 5350);
DISPLAY 0.872340 (-3502 5350);
PAINT GREEN (-3502 5350);
DISPLAY INVISIBLE (-3502 5350);
FORCEADD TAP..1
(-3500 5300);
FORCEPROP 3 LASTPIN (-3550 5300) SIG_NAME M_C_CPU0_SA_DQ<12>
J 0
(-3540 5310);
DISPLAY 0.659574 (-3540 5310);
PAINT MONO (-3540 5310);
DISPLAY INVISIBLE (-3540 5310);
FORCEPROP 1 LASTPIN (-3550 5300) BN 12
J 0
(-3562 5308);
DISPLAY 0.489362 (-3562 5308);
PAINT GREEN (-3562 5308);
FORCEPROP 2 LAST CDS_LIB mstr_standard
J 0
(-3500 5300);
DISPLAY 0.723404 (-3500 5300);
PAINT MONO (-3500 5300);
DISPLAY INVISIBLE (-3500 5300);
FORCEPROP 1 LAST BODY_TYPE PLUMBING
J 0
(-3500 5350);
DISPLAY 0.872340 (-3500 5350);
PAINT GREEN (-3500 5350);
DISPLAY INVISIBLE (-3500 5350);
FORCEPROP 1 LAST HDL_TAP TRUE
J 0
(-3175 5175);
DISPLAY 0.872340 (-3175 5175);
DISPLAY INVISIBLE (-3175 5175);
FORCEPROP 1 LAST PATH I174
J 0
(-3502 5300);
DISPLAY 0.872340 (-3502 5300);
PAINT GREEN (-3502 5300);
DISPLAY INVISIBLE (-3502 5300);
FORCEADD TAP..1
(-3500 5250);
FORCEPROP 3 LASTPIN (-3550 5250) SIG_NAME M_C_CPU0_SA_DQ<13>
J 0
(-3540 5260);
DISPLAY 0.659574 (-3540 5260);
PAINT MONO (-3540 5260);
DISPLAY INVISIBLE (-3540 5260);
FORCEPROP 1 LASTPIN (-3550 5250) BN 13
J 0
(-3562 5258);
DISPLAY 0.489362 (-3562 5258);
PAINT GREEN (-3562 5258);
FORCEPROP 2 LAST CDS_LIB mstr_standard
J 0
(-3500 5250);
DISPLAY 0.723404 (-3500 5250);
PAINT MONO (-3500 5250);
DISPLAY INVISIBLE (-3500 5250);
FORCEPROP 1 LAST BODY_TYPE PLUMBING
J 0
(-3500 5300);
DISPLAY 0.872340 (-3500 5300);
PAINT GREEN (-3500 5300);
DISPLAY INVISIBLE (-3500 5300);
FORCEPROP 1 LAST HDL_TAP TRUE
J 0
(-3175 5125);
DISPLAY 0.872340 (-3175 5125);
DISPLAY INVISIBLE (-3175 5125);
FORCEPROP 1 LAST PATH I175
J 0
(-3502 5250);
DISPLAY 0.872340 (-3502 5250);
PAINT GREEN (-3502 5250);
DISPLAY INVISIBLE (-3502 5250);
FORCEADD TAP..1
(-3500 5200);
FORCEPROP 3 LASTPIN (-3550 5200) SIG_NAME M_C_CPU0_SA_DQ<14>
J 0
(-3540 5210);
DISPLAY 0.659574 (-3540 5210);
PAINT MONO (-3540 5210);
DISPLAY INVISIBLE (-3540 5210);
FORCEPROP 1 LASTPIN (-3550 5200) BN 14
J 0
(-3562 5208);
DISPLAY 0.489362 (-3562 5208);
PAINT GREEN (-3562 5208);
FORCEPROP 2 LAST CDS_LIB mstr_standard
J 0
(-3500 5200);
DISPLAY 0.723404 (-3500 5200);
PAINT MONO (-3500 5200);
DISPLAY INVISIBLE (-3500 5200);
FORCEPROP 1 LAST BODY_TYPE PLUMBING
J 0
(-3500 5250);
DISPLAY 0.872340 (-3500 5250);
PAINT GREEN (-3500 5250);
DISPLAY INVISIBLE (-3500 5250);
FORCEPROP 1 LAST HDL_TAP TRUE
J 0
(-3175 5075);
DISPLAY 0.872340 (-3175 5075);
DISPLAY INVISIBLE (-3175 5075);
FORCEPROP 1 LAST PATH I176
J 0
(-3502 5200);
DISPLAY 0.872340 (-3502 5200);
PAINT GREEN (-3502 5200);
DISPLAY INVISIBLE (-3502 5200);
FORCEADD TAP..1
(-3500 5150);
FORCEPROP 3 LASTPIN (-3550 5150) SIG_NAME M_C_CPU0_SA_DQ<15>
J 0
(-3540 5160);
DISPLAY 0.659574 (-3540 5160);
PAINT MONO (-3540 5160);
DISPLAY INVISIBLE (-3540 5160);
FORCEPROP 1 LASTPIN (-3550 5150) BN 15
J 0
(-3562 5158);
DISPLAY 0.489362 (-3562 5158);
PAINT GREEN (-3562 5158);
FORCEPROP 2 LAST CDS_LIB mstr_standard
J 0
(-3500 5150);
DISPLAY 0.723404 (-3500 5150);
PAINT MONO (-3500 5150);
DISPLAY INVISIBLE (-3500 5150);
FORCEPROP 1 LAST BODY_TYPE PLUMBING
J 0
(-3500 5200);
DISPLAY 0.872340 (-3500 5200);
PAINT GREEN (-3500 5200);
DISPLAY INVISIBLE (-3500 5200);
FORCEPROP 1 LAST HDL_TAP TRUE
J 0
(-3175 5025);
DISPLAY 0.872340 (-3175 5025);
DISPLAY INVISIBLE (-3175 5025);
FORCEPROP 1 LAST PATH I177
J 0
(-3502 5150);
DISPLAY 0.872340 (-3502 5150);
PAINT GREEN (-3502 5150);
DISPLAY INVISIBLE (-3502 5150);
FORCEADD TAP..1
(-3500 5050);
FORCEPROP 3 LASTPIN (-3550 5050) SIG_NAME M_C_CPU0_SA_DQ<16>
J 0
(-3540 5060);
DISPLAY 0.659574 (-3540 5060);
PAINT MONO (-3540 5060);
DISPLAY INVISIBLE (-3540 5060);
FORCEPROP 1 LASTPIN (-3550 5050) BN 16
J 0
(-3562 5058);
DISPLAY 0.489362 (-3562 5058);
PAINT GREEN (-3562 5058);
FORCEPROP 2 LAST CDS_LIB mstr_standard
J 0
(-3500 5050);
DISPLAY 0.723404 (-3500 5050);
PAINT MONO (-3500 5050);
DISPLAY INVISIBLE (-3500 5050);
FORCEPROP 1 LAST BODY_TYPE PLUMBING
J 0
(-3500 5100);
DISPLAY 0.872340 (-3500 5100);
PAINT GREEN (-3500 5100);
DISPLAY INVISIBLE (-3500 5100);
FORCEPROP 1 LAST HDL_TAP TRUE
J 0
(-3175 4925);
DISPLAY 0.872340 (-3175 4925);
DISPLAY INVISIBLE (-3175 4925);
FORCEPROP 1 LAST PATH I178
J 0
(-3502 5050);
DISPLAY 0.872340 (-3502 5050);
PAINT GREEN (-3502 5050);
DISPLAY INVISIBLE (-3502 5050);
FORCEADD TAP..1
(-3500 5000);
FORCEPROP 3 LASTPIN (-3550 5000) SIG_NAME M_C_CPU0_SA_DQ<17>
J 0
(-3540 5010);
DISPLAY 0.659574 (-3540 5010);
PAINT MONO (-3540 5010);
DISPLAY INVISIBLE (-3540 5010);
FORCEPROP 1 LASTPIN (-3550 5000) BN 17
J 0
(-3562 5008);
DISPLAY 0.489362 (-3562 5008);
PAINT GREEN (-3562 5008);
FORCEPROP 2 LAST CDS_LIB mstr_standard
J 0
(-3500 5000);
DISPLAY 0.723404 (-3500 5000);
PAINT MONO (-3500 5000);
DISPLAY INVISIBLE (-3500 5000);
FORCEPROP 1 LAST BODY_TYPE PLUMBING
J 0
(-3500 5050);
DISPLAY 0.872340 (-3500 5050);
PAINT GREEN (-3500 5050);
DISPLAY INVISIBLE (-3500 5050);
FORCEPROP 1 LAST HDL_TAP TRUE
J 0
(-3175 4875);
DISPLAY 0.872340 (-3175 4875);
DISPLAY INVISIBLE (-3175 4875);
FORCEPROP 1 LAST PATH I179
J 0
(-3502 5000);
DISPLAY 0.872340 (-3502 5000);
PAINT GREEN (-3502 5000);
DISPLAY INVISIBLE (-3502 5000);
FORCEADD TAP..1
(-3500 4950);
FORCEPROP 3 LASTPIN (-3550 4950) SIG_NAME M_C_CPU0_SA_DQ<18>
J 0
(-3540 4960);
DISPLAY 0.659574 (-3540 4960);
PAINT MONO (-3540 4960);
DISPLAY INVISIBLE (-3540 4960);
FORCEPROP 1 LASTPIN (-3550 4950) BN 18
J 0
(-3562 4958);
DISPLAY 0.489362 (-3562 4958);
PAINT GREEN (-3562 4958);
FORCEPROP 2 LAST CDS_LIB mstr_standard
J 0
(-3500 4950);
DISPLAY 0.723404 (-3500 4950);
PAINT MONO (-3500 4950);
DISPLAY INVISIBLE (-3500 4950);
FORCEPROP 1 LAST BODY_TYPE PLUMBING
J 0
(-3500 5000);
DISPLAY 0.872340 (-3500 5000);
PAINT GREEN (-3500 5000);
DISPLAY INVISIBLE (-3500 5000);
FORCEPROP 1 LAST HDL_TAP TRUE
J 0
(-3175 4825);
DISPLAY 0.872340 (-3175 4825);
DISPLAY INVISIBLE (-3175 4825);
FORCEPROP 1 LAST PATH I180
J 0
(-3502 4950);
DISPLAY 0.872340 (-3502 4950);
PAINT GREEN (-3502 4950);
DISPLAY INVISIBLE (-3502 4950);
FORCEADD TAP..1
(-3500 4900);
FORCEPROP 3 LASTPIN (-3550 4900) SIG_NAME M_C_CPU0_SA_DQ<19>
J 0
(-3540 4910);
DISPLAY 0.659574 (-3540 4910);
PAINT MONO (-3540 4910);
DISPLAY INVISIBLE (-3540 4910);
FORCEPROP 1 LASTPIN (-3550 4900) BN 19
J 0
(-3562 4908);
DISPLAY 0.489362 (-3562 4908);
PAINT GREEN (-3562 4908);
FORCEPROP 2 LAST CDS_LIB mstr_standard
J 0
(-3500 4900);
DISPLAY 0.723404 (-3500 4900);
PAINT MONO (-3500 4900);
DISPLAY INVISIBLE (-3500 4900);
FORCEPROP 1 LAST BODY_TYPE PLUMBING
J 0
(-3500 4950);
DISPLAY 0.872340 (-3500 4950);
PAINT GREEN (-3500 4950);
DISPLAY INVISIBLE (-3500 4950);
FORCEPROP 1 LAST HDL_TAP TRUE
J 0
(-3175 4775);
DISPLAY 0.872340 (-3175 4775);
DISPLAY INVISIBLE (-3175 4775);
FORCEPROP 1 LAST PATH I181
J 0
(-3502 4900);
DISPLAY 0.872340 (-3502 4900);
PAINT GREEN (-3502 4900);
DISPLAY INVISIBLE (-3502 4900);
FORCEADD TAP..1
(-3500 4850);
FORCEPROP 3 LASTPIN (-3550 4850) SIG_NAME M_C_CPU0_SA_DQ<20>
J 0
(-3540 4860);
DISPLAY 0.659574 (-3540 4860);
PAINT MONO (-3540 4860);
DISPLAY INVISIBLE (-3540 4860);
FORCEPROP 1 LASTPIN (-3550 4850) BN 20
J 0
(-3562 4858);
DISPLAY 0.489362 (-3562 4858);
PAINT GREEN (-3562 4858);
FORCEPROP 2 LAST CDS_LIB mstr_standard
J 0
(-3500 4850);
DISPLAY 0.723404 (-3500 4850);
PAINT MONO (-3500 4850);
DISPLAY INVISIBLE (-3500 4850);
FORCEPROP 1 LAST BODY_TYPE PLUMBING
J 0
(-3500 4900);
DISPLAY 0.872340 (-3500 4900);
PAINT GREEN (-3500 4900);
DISPLAY INVISIBLE (-3500 4900);
FORCEPROP 1 LAST HDL_TAP TRUE
J 0
(-3175 4725);
DISPLAY 0.872340 (-3175 4725);
DISPLAY INVISIBLE (-3175 4725);
FORCEPROP 1 LAST PATH I182
J 0
(-3502 4850);
DISPLAY 0.872340 (-3502 4850);
PAINT GREEN (-3502 4850);
DISPLAY INVISIBLE (-3502 4850);
FORCEADD TAP..1
(-3500 4800);
FORCEPROP 3 LASTPIN (-3550 4800) SIG_NAME M_C_CPU0_SA_DQ<21>
J 0
(-3540 4810);
DISPLAY 0.659574 (-3540 4810);
PAINT MONO (-3540 4810);
DISPLAY INVISIBLE (-3540 4810);
FORCEPROP 1 LASTPIN (-3550 4800) BN 21
J 0
(-3562 4808);
DISPLAY 0.489362 (-3562 4808);
PAINT GREEN (-3562 4808);
FORCEPROP 2 LAST CDS_LIB mstr_standard
J 0
(-3500 4800);
DISPLAY 0.723404 (-3500 4800);
PAINT MONO (-3500 4800);
DISPLAY INVISIBLE (-3500 4800);
FORCEPROP 1 LAST BODY_TYPE PLUMBING
J 0
(-3500 4850);
DISPLAY 0.872340 (-3500 4850);
PAINT GREEN (-3500 4850);
DISPLAY INVISIBLE (-3500 4850);
FORCEPROP 1 LAST HDL_TAP TRUE
J 0
(-3175 4675);
DISPLAY 0.872340 (-3175 4675);
DISPLAY INVISIBLE (-3175 4675);
FORCEPROP 1 LAST PATH I183
J 0
(-3502 4800);
DISPLAY 0.872340 (-3502 4800);
PAINT GREEN (-3502 4800);
DISPLAY INVISIBLE (-3502 4800);
FORCEADD TAP..1
(-3500 4750);
FORCEPROP 3 LASTPIN (-3550 4750) SIG_NAME M_C_CPU0_SA_DQ<22>
J 0
(-3540 4760);
DISPLAY 0.659574 (-3540 4760);
PAINT MONO (-3540 4760);
DISPLAY INVISIBLE (-3540 4760);
FORCEPROP 1 LASTPIN (-3550 4750) BN 22
J 0
(-3562 4758);
DISPLAY 0.489362 (-3562 4758);
PAINT GREEN (-3562 4758);
FORCEPROP 2 LAST CDS_LIB mstr_standard
J 0
(-3500 4750);
DISPLAY 0.723404 (-3500 4750);
PAINT MONO (-3500 4750);
DISPLAY INVISIBLE (-3500 4750);
FORCEPROP 1 LAST BODY_TYPE PLUMBING
J 0
(-3500 4800);
DISPLAY 0.872340 (-3500 4800);
PAINT GREEN (-3500 4800);
DISPLAY INVISIBLE (-3500 4800);
FORCEPROP 1 LAST HDL_TAP TRUE
J 0
(-3175 4625);
DISPLAY 0.872340 (-3175 4625);
DISPLAY INVISIBLE (-3175 4625);
FORCEPROP 1 LAST PATH I184
J 0
(-3502 4750);
DISPLAY 0.872340 (-3502 4750);
PAINT GREEN (-3502 4750);
DISPLAY INVISIBLE (-3502 4750);
FORCEADD TAP..1
(-3500 4700);
FORCEPROP 3 LASTPIN (-3550 4700) SIG_NAME M_C_CPU0_SA_DQ<23>
J 0
(-3540 4710);
DISPLAY 0.659574 (-3540 4710);
PAINT MONO (-3540 4710);
DISPLAY INVISIBLE (-3540 4710);
FORCEPROP 1 LASTPIN (-3550 4700) BN 23
J 0
(-3562 4708);
DISPLAY 0.489362 (-3562 4708);
PAINT GREEN (-3562 4708);
FORCEPROP 2 LAST CDS_LIB mstr_standard
J 0
(-3500 4700);
DISPLAY 0.723404 (-3500 4700);
PAINT MONO (-3500 4700);
DISPLAY INVISIBLE (-3500 4700);
FORCEPROP 1 LAST BODY_TYPE PLUMBING
J 0
(-3500 4750);
DISPLAY 0.872340 (-3500 4750);
PAINT GREEN (-3500 4750);
DISPLAY INVISIBLE (-3500 4750);
FORCEPROP 1 LAST HDL_TAP TRUE
J 0
(-3175 4575);
DISPLAY 0.872340 (-3175 4575);
DISPLAY INVISIBLE (-3175 4575);
FORCEPROP 1 LAST PATH I185
J 0
(-3502 4700);
DISPLAY 0.872340 (-3502 4700);
PAINT GREEN (-3502 4700);
DISPLAY INVISIBLE (-3502 4700);
FORCEADD TAP..1
(-3500 4600);
FORCEPROP 3 LASTPIN (-3550 4600) SIG_NAME M_C_CPU0_SA_DQ<24>
J 0
(-3540 4610);
DISPLAY 0.659574 (-3540 4610);
PAINT MONO (-3540 4610);
DISPLAY INVISIBLE (-3540 4610);
FORCEPROP 1 LASTPIN (-3550 4600) BN 24
J 0
(-3562 4608);
DISPLAY 0.489362 (-3562 4608);
PAINT GREEN (-3562 4608);
FORCEPROP 2 LAST CDS_LIB mstr_standard
J 0
(-3500 4600);
DISPLAY 0.723404 (-3500 4600);
PAINT MONO (-3500 4600);
DISPLAY INVISIBLE (-3500 4600);
FORCEPROP 1 LAST BODY_TYPE PLUMBING
J 0
(-3500 4650);
DISPLAY 0.872340 (-3500 4650);
PAINT GREEN (-3500 4650);
DISPLAY INVISIBLE (-3500 4650);
FORCEPROP 1 LAST HDL_TAP TRUE
J 0
(-3175 4475);
DISPLAY 0.872340 (-3175 4475);
DISPLAY INVISIBLE (-3175 4475);
FORCEPROP 1 LAST PATH I186
J 0
(-3502 4600);
DISPLAY 0.872340 (-3502 4600);
PAINT GREEN (-3502 4600);
DISPLAY INVISIBLE (-3502 4600);
FORCEADD TAP..1
(-3500 4550);
FORCEPROP 3 LASTPIN (-3550 4550) SIG_NAME M_C_CPU0_SA_DQ<25>
J 0
(-3540 4560);
DISPLAY 0.659574 (-3540 4560);
PAINT MONO (-3540 4560);
DISPLAY INVISIBLE (-3540 4560);
FORCEPROP 1 LASTPIN (-3550 4550) BN 25
J 0
(-3562 4558);
DISPLAY 0.489362 (-3562 4558);
PAINT GREEN (-3562 4558);
FORCEPROP 2 LAST CDS_LIB mstr_standard
J 0
(-3500 4550);
DISPLAY 0.723404 (-3500 4550);
PAINT MONO (-3500 4550);
DISPLAY INVISIBLE (-3500 4550);
FORCEPROP 1 LAST BODY_TYPE PLUMBING
J 0
(-3500 4600);
DISPLAY 0.872340 (-3500 4600);
PAINT GREEN (-3500 4600);
DISPLAY INVISIBLE (-3500 4600);
FORCEPROP 1 LAST HDL_TAP TRUE
J 0
(-3175 4425);
DISPLAY 0.872340 (-3175 4425);
DISPLAY INVISIBLE (-3175 4425);
FORCEPROP 1 LAST PATH I187
J 0
(-3502 4550);
DISPLAY 0.872340 (-3502 4550);
PAINT GREEN (-3502 4550);
DISPLAY INVISIBLE (-3502 4550);
FORCEADD TAP..1
(-3500 4500);
FORCEPROP 3 LASTPIN (-3550 4500) SIG_NAME M_C_CPU0_SA_DQ<26>
J 0
(-3540 4510);
DISPLAY 0.659574 (-3540 4510);
PAINT MONO (-3540 4510);
DISPLAY INVISIBLE (-3540 4510);
FORCEPROP 1 LASTPIN (-3550 4500) BN 26
J 0
(-3562 4508);
DISPLAY 0.489362 (-3562 4508);
PAINT GREEN (-3562 4508);
FORCEPROP 2 LAST CDS_LIB mstr_standard
J 0
(-3500 4500);
DISPLAY 0.723404 (-3500 4500);
PAINT MONO (-3500 4500);
DISPLAY INVISIBLE (-3500 4500);
FORCEPROP 1 LAST BODY_TYPE PLUMBING
J 0
(-3500 4550);
DISPLAY 0.872340 (-3500 4550);
PAINT GREEN (-3500 4550);
DISPLAY INVISIBLE (-3500 4550);
FORCEPROP 1 LAST HDL_TAP TRUE
J 0
(-3175 4375);
DISPLAY 0.872340 (-3175 4375);
DISPLAY INVISIBLE (-3175 4375);
FORCEPROP 1 LAST PATH I188
J 0
(-3502 4500);
DISPLAY 0.872340 (-3502 4500);
PAINT GREEN (-3502 4500);
DISPLAY INVISIBLE (-3502 4500);
FORCEADD TAP..1
(-3500 4450);
FORCEPROP 3 LASTPIN (-3550 4450) SIG_NAME M_C_CPU0_SA_DQ<27>
J 0
(-3540 4460);
DISPLAY 0.659574 (-3540 4460);
PAINT MONO (-3540 4460);
DISPLAY INVISIBLE (-3540 4460);
FORCEPROP 1 LASTPIN (-3550 4450) BN 27
J 0
(-3562 4458);
DISPLAY 0.489362 (-3562 4458);
PAINT GREEN (-3562 4458);
FORCEPROP 2 LAST CDS_LIB mstr_standard
J 0
(-3500 4450);
DISPLAY 0.723404 (-3500 4450);
PAINT MONO (-3500 4450);
DISPLAY INVISIBLE (-3500 4450);
FORCEPROP 1 LAST BODY_TYPE PLUMBING
J 0
(-3500 4500);
DISPLAY 0.872340 (-3500 4500);
PAINT GREEN (-3500 4500);
DISPLAY INVISIBLE (-3500 4500);
FORCEPROP 1 LAST HDL_TAP TRUE
J 0
(-3175 4325);
DISPLAY 0.872340 (-3175 4325);
DISPLAY INVISIBLE (-3175 4325);
FORCEPROP 1 LAST PATH I189
J 0
(-3502 4450);
DISPLAY 0.872340 (-3502 4450);
PAINT GREEN (-3502 4450);
DISPLAY INVISIBLE (-3502 4450);
FORCEADD TAP..1
(-3500 4400);
FORCEPROP 3 LASTPIN (-3550 4400) SIG_NAME M_C_CPU0_SA_DQ<28>
J 0
(-3540 4410);
DISPLAY 0.659574 (-3540 4410);
PAINT MONO (-3540 4410);
DISPLAY INVISIBLE (-3540 4410);
FORCEPROP 1 LASTPIN (-3550 4400) BN 28
J 0
(-3562 4408);
DISPLAY 0.489362 (-3562 4408);
PAINT GREEN (-3562 4408);
FORCEPROP 2 LAST CDS_LIB mstr_standard
J 0
(-3500 4400);
DISPLAY 0.723404 (-3500 4400);
PAINT MONO (-3500 4400);
DISPLAY INVISIBLE (-3500 4400);
FORCEPROP 1 LAST BODY_TYPE PLUMBING
J 0
(-3500 4450);
DISPLAY 0.872340 (-3500 4450);
PAINT GREEN (-3500 4450);
DISPLAY INVISIBLE (-3500 4450);
FORCEPROP 1 LAST HDL_TAP TRUE
J 0
(-3175 4275);
DISPLAY 0.872340 (-3175 4275);
DISPLAY INVISIBLE (-3175 4275);
FORCEPROP 1 LAST PATH I190
J 0
(-3502 4400);
DISPLAY 0.872340 (-3502 4400);
PAINT GREEN (-3502 4400);
DISPLAY INVISIBLE (-3502 4400);
FORCEADD TAP..1
(-3500 4350);
FORCEPROP 3 LASTPIN (-3550 4350) SIG_NAME M_C_CPU0_SA_DQ<29>
J 0
(-3540 4360);
DISPLAY 0.659574 (-3540 4360);
PAINT MONO (-3540 4360);
DISPLAY INVISIBLE (-3540 4360);
FORCEPROP 1 LASTPIN (-3550 4350) BN 29
J 0
(-3562 4358);
DISPLAY 0.489362 (-3562 4358);
PAINT GREEN (-3562 4358);
FORCEPROP 2 LAST CDS_LIB mstr_standard
J 0
(-3500 4350);
DISPLAY 0.723404 (-3500 4350);
PAINT MONO (-3500 4350);
DISPLAY INVISIBLE (-3500 4350);
FORCEPROP 1 LAST BODY_TYPE PLUMBING
J 0
(-3500 4400);
DISPLAY 0.872340 (-3500 4400);
PAINT GREEN (-3500 4400);
DISPLAY INVISIBLE (-3500 4400);
FORCEPROP 1 LAST HDL_TAP TRUE
J 0
(-3175 4225);
DISPLAY 0.872340 (-3175 4225);
DISPLAY INVISIBLE (-3175 4225);
FORCEPROP 1 LAST PATH I191
J 0
(-3502 4350);
DISPLAY 0.872340 (-3502 4350);
PAINT GREEN (-3502 4350);
DISPLAY INVISIBLE (-3502 4350);
FORCEADD TAP..1
(-3500 4300);
FORCEPROP 3 LASTPIN (-3550 4300) SIG_NAME M_C_CPU0_SA_DQ<30>
J 0
(-3540 4310);
DISPLAY 0.659574 (-3540 4310);
PAINT MONO (-3540 4310);
DISPLAY INVISIBLE (-3540 4310);
FORCEPROP 1 LASTPIN (-3550 4300) BN 30
J 0
(-3562 4308);
DISPLAY 0.489362 (-3562 4308);
PAINT GREEN (-3562 4308);
FORCEPROP 2 LAST CDS_LIB mstr_standard
J 0
(-3500 4300);
DISPLAY 0.723404 (-3500 4300);
PAINT MONO (-3500 4300);
DISPLAY INVISIBLE (-3500 4300);
FORCEPROP 1 LAST BODY_TYPE PLUMBING
J 0
(-3500 4350);
DISPLAY 0.872340 (-3500 4350);
PAINT GREEN (-3500 4350);
DISPLAY INVISIBLE (-3500 4350);
FORCEPROP 1 LAST HDL_TAP TRUE
J 0
(-3175 4175);
DISPLAY 0.872340 (-3175 4175);
DISPLAY INVISIBLE (-3175 4175);
FORCEPROP 1 LAST PATH I192
J 0
(-3502 4300);
DISPLAY 0.872340 (-3502 4300);
PAINT GREEN (-3502 4300);
DISPLAY INVISIBLE (-3502 4300);
FORCEADD TAP..1
(-3500 4250);
FORCEPROP 3 LASTPIN (-3550 4250) SIG_NAME M_C_CPU0_SA_DQ<31>
J 0
(-3540 4260);
DISPLAY 0.659574 (-3540 4260);
PAINT MONO (-3540 4260);
DISPLAY INVISIBLE (-3540 4260);
FORCEPROP 1 LASTPIN (-3550 4250) BN 31
J 0
(-3562 4258);
DISPLAY 0.489362 (-3562 4258);
PAINT GREEN (-3562 4258);
FORCEPROP 2 LAST CDS_LIB mstr_standard
J 0
(-3500 4250);
DISPLAY 0.723404 (-3500 4250);
PAINT MONO (-3500 4250);
DISPLAY INVISIBLE (-3500 4250);
FORCEPROP 1 LAST BODY_TYPE PLUMBING
J 0
(-3500 4300);
DISPLAY 0.872340 (-3500 4300);
PAINT GREEN (-3500 4300);
DISPLAY INVISIBLE (-3500 4300);
FORCEPROP 1 LAST HDL_TAP TRUE
J 0
(-3175 4125);
DISPLAY 0.872340 (-3175 4125);
DISPLAY INVISIBLE (-3175 4125);
FORCEPROP 1 LAST PATH I193
J 0
(-3502 4250);
DISPLAY 0.872340 (-3502 4250);
PAINT GREEN (-3502 4250);
DISPLAY INVISIBLE (-3502 4250);
FORCEADD TAP..1
(-3500 4100);
FORCEPROP 3 LASTPIN (-3550 4100) SIG_NAME M_C_CPU0_SB_DQ<1>
J 0
(-3540 4110);
DISPLAY 0.659574 (-3540 4110);
PAINT MONO (-3540 4110);
DISPLAY INVISIBLE (-3540 4110);
FORCEPROP 1 LASTPIN (-3550 4100) BN 1
J 0
(-3562 4108);
DISPLAY 0.489362 (-3562 4108);
PAINT GREEN (-3562 4108);
FORCEPROP 2 LAST CDS_LIB mstr_standard
J 0
(-3500 4100);
DISPLAY 0.723404 (-3500 4100);
PAINT MONO (-3500 4100);
DISPLAY INVISIBLE (-3500 4100);
FORCEPROP 1 LAST BODY_TYPE PLUMBING
J 0
(-3500 4150);
DISPLAY 0.872340 (-3500 4150);
PAINT GREEN (-3500 4150);
DISPLAY INVISIBLE (-3500 4150);
FORCEPROP 1 LAST HDL_TAP TRUE
J 0
(-3175 3975);
DISPLAY 0.872340 (-3175 3975);
DISPLAY INVISIBLE (-3175 3975);
FORCEPROP 1 LAST PATH I194
J 0
(-3502 4100);
DISPLAY 0.872340 (-3502 4100);
PAINT GREEN (-3502 4100);
DISPLAY INVISIBLE (-3502 4100);
FORCEADD TAP..1
(-3500 4150);
FORCEPROP 3 LASTPIN (-3550 4150) SIG_NAME M_C_CPU0_SB_DQ<0>
J 0
(-3540 4160);
DISPLAY 0.659574 (-3540 4160);
PAINT MONO (-3540 4160);
DISPLAY INVISIBLE (-3540 4160);
FORCEPROP 1 LASTPIN (-3550 4150) BN 0
J 0
(-3562 4158);
DISPLAY 0.489362 (-3562 4158);
PAINT GREEN (-3562 4158);
FORCEPROP 2 LAST CDS_LIB mstr_standard
J 0
(-3500 4150);
DISPLAY 0.723404 (-3500 4150);
PAINT MONO (-3500 4150);
DISPLAY INVISIBLE (-3500 4150);
FORCEPROP 1 LAST BODY_TYPE PLUMBING
J 0
(-3500 4200);
DISPLAY 0.872340 (-3500 4200);
PAINT GREEN (-3500 4200);
DISPLAY INVISIBLE (-3500 4200);
FORCEPROP 1 LAST HDL_TAP TRUE
J 0
(-3175 4025);
DISPLAY 0.872340 (-3175 4025);
DISPLAY INVISIBLE (-3175 4025);
FORCEPROP 1 LAST PATH I195
J 0
(-3502 4150);
DISPLAY 0.872340 (-3502 4150);
PAINT GREEN (-3502 4150);
DISPLAY INVISIBLE (-3502 4150);
FORCEADD OFFPAGE..6
R 2
(-2900 2400);
FORCEPROP 2 LAST $XR0 87 
J 0
(-2686 2400);
DISPLAY 0.638298 (-2686 2400);
PAINT MONO (-2686 2400);
FORCEPROP 2 LAST PATH I196
J 0
(-2675 2450);
DISPLAY 1.021277 (-2675 2450);
DISPLAY INVISIBLE (-2675 2450);
FORCEPROP 1 LAST COMMENT_BODY TRUE
J 2
(-3000 2325);
DISPLAY 0.872340 (-3000 2325);
PAINT GREEN (-3000 2325);
DISPLAY INVISIBLE (-3000 2325);
FORCEPROP 1 LAST OFFPAGE TRUE
J 2
(-3225 2275);
DISPLAY 0.872340 (-3225 2275);
PAINT GREEN (-3225 2275);
DISPLAY INVISIBLE (-3225 2275);
FORCEPROP 2 LAST CDS_LIB mstr_standard
J 2
(-2900 2400);
DISPLAY 0.723404 (-2900 2400);
PAINT MONO (-2900 2400);
DISPLAY INVISIBLE (-2900 2400);
FORCEADD TAP..1
(-3500 4050);
FORCEPROP 3 LASTPIN (-3550 4050) SIG_NAME M_C_CPU0_SB_DQ<2>
J 0
(-3540 4060);
DISPLAY 0.659574 (-3540 4060);
PAINT MONO (-3540 4060);
DISPLAY INVISIBLE (-3540 4060);
FORCEPROP 1 LASTPIN (-3550 4050) BN 2
J 0
(-3562 4058);
DISPLAY 0.489362 (-3562 4058);
PAINT GREEN (-3562 4058);
FORCEPROP 2 LAST CDS_LIB mstr_standard
J 0
(-3500 4050);
DISPLAY 0.723404 (-3500 4050);
PAINT MONO (-3500 4050);
DISPLAY INVISIBLE (-3500 4050);
FORCEPROP 1 LAST BODY_TYPE PLUMBING
J 0
(-3500 4100);
DISPLAY 0.872340 (-3500 4100);
PAINT GREEN (-3500 4100);
DISPLAY INVISIBLE (-3500 4100);
FORCEPROP 1 LAST HDL_TAP TRUE
J 0
(-3175 3925);
DISPLAY 0.872340 (-3175 3925);
DISPLAY INVISIBLE (-3175 3925);
FORCEPROP 1 LAST PATH I197
J 0
(-3502 4050);
DISPLAY 0.872340 (-3502 4050);
PAINT GREEN (-3502 4050);
DISPLAY INVISIBLE (-3502 4050);
FORCEADD TAP..1
(-3500 4000);
FORCEPROP 3 LASTPIN (-3550 4000) SIG_NAME M_C_CPU0_SB_DQ<3>
J 0
(-3540 4010);
DISPLAY 0.659574 (-3540 4010);
PAINT MONO (-3540 4010);
DISPLAY INVISIBLE (-3540 4010);
FORCEPROP 1 LASTPIN (-3550 4000) BN 3
J 0
(-3562 4008);
DISPLAY 0.489362 (-3562 4008);
PAINT GREEN (-3562 4008);
FORCEPROP 2 LAST CDS_LIB mstr_standard
J 0
(-3500 4000);
DISPLAY 0.723404 (-3500 4000);
PAINT MONO (-3500 4000);
DISPLAY INVISIBLE (-3500 4000);
FORCEPROP 1 LAST BODY_TYPE PLUMBING
J 0
(-3500 4050);
DISPLAY 0.872340 (-3500 4050);
PAINT GREEN (-3500 4050);
DISPLAY INVISIBLE (-3500 4050);
FORCEPROP 1 LAST HDL_TAP TRUE
J 0
(-3175 3875);
DISPLAY 0.872340 (-3175 3875);
DISPLAY INVISIBLE (-3175 3875);
FORCEPROP 1 LAST PATH I198
J 0
(-3502 4000);
DISPLAY 0.872340 (-3502 4000);
PAINT GREEN (-3502 4000);
DISPLAY INVISIBLE (-3502 4000);
FORCEADD TAP..1
(-3500 3950);
FORCEPROP 3 LASTPIN (-3550 3950) SIG_NAME M_C_CPU0_SB_DQ<4>
J 0
(-3540 3960);
DISPLAY 0.659574 (-3540 3960);
PAINT MONO (-3540 3960);
DISPLAY INVISIBLE (-3540 3960);
FORCEPROP 1 LASTPIN (-3550 3950) BN 4
J 0
(-3562 3958);
DISPLAY 0.489362 (-3562 3958);
PAINT GREEN (-3562 3958);
FORCEPROP 2 LAST CDS_LIB mstr_standard
J 0
(-3500 3950);
DISPLAY 0.723404 (-3500 3950);
PAINT MONO (-3500 3950);
DISPLAY INVISIBLE (-3500 3950);
FORCEPROP 1 LAST BODY_TYPE PLUMBING
J 0
(-3500 4000);
DISPLAY 0.872340 (-3500 4000);
PAINT GREEN (-3500 4000);
DISPLAY INVISIBLE (-3500 4000);
FORCEPROP 1 LAST HDL_TAP TRUE
J 0
(-3175 3825);
DISPLAY 0.872340 (-3175 3825);
DISPLAY INVISIBLE (-3175 3825);
FORCEPROP 1 LAST PATH I199
J 0
(-3502 3950);
DISPLAY 0.872340 (-3502 3950);
PAINT GREEN (-3502 3950);
DISPLAY INVISIBLE (-3502 3950);
FORCEADD TAP..1
(-3500 3900);
FORCEPROP 3 LASTPIN (-3550 3900) SIG_NAME M_C_CPU0_SB_DQ<5>
J 0
(-3540 3910);
DISPLAY 0.659574 (-3540 3910);
PAINT MONO (-3540 3910);
DISPLAY INVISIBLE (-3540 3910);
FORCEPROP 1 LASTPIN (-3550 3900) BN 5
J 0
(-3562 3908);
DISPLAY 0.489362 (-3562 3908);
PAINT GREEN (-3562 3908);
FORCEPROP 2 LAST CDS_LIB mstr_standard
J 0
(-3500 3900);
DISPLAY 0.723404 (-3500 3900);
PAINT MONO (-3500 3900);
DISPLAY INVISIBLE (-3500 3900);
FORCEPROP 1 LAST BODY_TYPE PLUMBING
J 0
(-3500 3950);
DISPLAY 0.872340 (-3500 3950);
PAINT GREEN (-3500 3950);
DISPLAY INVISIBLE (-3500 3950);
FORCEPROP 1 LAST HDL_TAP TRUE
J 0
(-3175 3775);
DISPLAY 0.872340 (-3175 3775);
DISPLAY INVISIBLE (-3175 3775);
FORCEPROP 1 LAST PATH I200
J 0
(-3502 3900);
DISPLAY 0.872340 (-3502 3900);
PAINT GREEN (-3502 3900);
DISPLAY INVISIBLE (-3502 3900);
FORCEADD TAP..1
(-3500 3850);
FORCEPROP 3 LASTPIN (-3550 3850) SIG_NAME M_C_CPU0_SB_DQ<6>
J 0
(-3540 3860);
DISPLAY 0.659574 (-3540 3860);
PAINT MONO (-3540 3860);
DISPLAY INVISIBLE (-3540 3860);
FORCEPROP 1 LASTPIN (-3550 3850) BN 6
J 0
(-3562 3858);
DISPLAY 0.489362 (-3562 3858);
PAINT GREEN (-3562 3858);
FORCEPROP 2 LAST CDS_LIB mstr_standard
J 0
(-3500 3850);
DISPLAY 0.723404 (-3500 3850);
PAINT MONO (-3500 3850);
DISPLAY INVISIBLE (-3500 3850);
FORCEPROP 1 LAST BODY_TYPE PLUMBING
J 0
(-3500 3900);
DISPLAY 0.872340 (-3500 3900);
PAINT GREEN (-3500 3900);
DISPLAY INVISIBLE (-3500 3900);
FORCEPROP 1 LAST HDL_TAP TRUE
J 0
(-3175 3725);
DISPLAY 0.872340 (-3175 3725);
DISPLAY INVISIBLE (-3175 3725);
FORCEPROP 1 LAST PATH I201
J 0
(-3502 3850);
DISPLAY 0.872340 (-3502 3850);
PAINT GREEN (-3502 3850);
DISPLAY INVISIBLE (-3502 3850);
FORCEADD TAP..1
(-3500 3800);
FORCEPROP 3 LASTPIN (-3550 3800) SIG_NAME M_C_CPU0_SB_DQ<7>
J 0
(-3540 3810);
DISPLAY 0.659574 (-3540 3810);
PAINT MONO (-3540 3810);
DISPLAY INVISIBLE (-3540 3810);
FORCEPROP 1 LASTPIN (-3550 3800) BN 7
J 0
(-3562 3808);
DISPLAY 0.489362 (-3562 3808);
PAINT GREEN (-3562 3808);
FORCEPROP 2 LAST CDS_LIB mstr_standard
J 0
(-3500 3800);
DISPLAY 0.723404 (-3500 3800);
PAINT MONO (-3500 3800);
DISPLAY INVISIBLE (-3500 3800);
FORCEPROP 1 LAST BODY_TYPE PLUMBING
J 0
(-3500 3850);
DISPLAY 0.872340 (-3500 3850);
PAINT GREEN (-3500 3850);
DISPLAY INVISIBLE (-3500 3850);
FORCEPROP 1 LAST HDL_TAP TRUE
J 0
(-3175 3675);
DISPLAY 0.872340 (-3175 3675);
DISPLAY INVISIBLE (-3175 3675);
FORCEPROP 1 LAST PATH I202
J 0
(-3502 3800);
DISPLAY 0.872340 (-3502 3800);
PAINT GREEN (-3502 3800);
DISPLAY INVISIBLE (-3502 3800);
FORCEADD TAP..1
(-3500 3700);
FORCEPROP 3 LASTPIN (-3550 3700) SIG_NAME M_C_CPU0_SB_DQ<8>
J 0
(-3540 3710);
DISPLAY 0.659574 (-3540 3710);
PAINT MONO (-3540 3710);
DISPLAY INVISIBLE (-3540 3710);
FORCEPROP 1 LASTPIN (-3550 3700) BN 8
J 0
(-3562 3708);
DISPLAY 0.489362 (-3562 3708);
PAINT GREEN (-3562 3708);
FORCEPROP 2 LAST CDS_LIB mstr_standard
J 0
(-3500 3700);
DISPLAY 0.723404 (-3500 3700);
PAINT MONO (-3500 3700);
DISPLAY INVISIBLE (-3500 3700);
FORCEPROP 1 LAST BODY_TYPE PLUMBING
J 0
(-3500 3750);
DISPLAY 0.872340 (-3500 3750);
PAINT GREEN (-3500 3750);
DISPLAY INVISIBLE (-3500 3750);
FORCEPROP 1 LAST HDL_TAP TRUE
J 0
(-3175 3575);
DISPLAY 0.872340 (-3175 3575);
DISPLAY INVISIBLE (-3175 3575);
FORCEPROP 1 LAST PATH I203
J 0
(-3502 3700);
DISPLAY 0.872340 (-3502 3700);
PAINT GREEN (-3502 3700);
DISPLAY INVISIBLE (-3502 3700);
FORCEADD TAP..1
(-3500 3650);
FORCEPROP 3 LASTPIN (-3550 3650) SIG_NAME M_C_CPU0_SB_DQ<9>
J 0
(-3540 3660);
DISPLAY 0.659574 (-3540 3660);
PAINT MONO (-3540 3660);
DISPLAY INVISIBLE (-3540 3660);
FORCEPROP 1 LASTPIN (-3550 3650) BN 9
J 0
(-3562 3658);
DISPLAY 0.489362 (-3562 3658);
PAINT GREEN (-3562 3658);
FORCEPROP 2 LAST CDS_LIB mstr_standard
J 0
(-3500 3650);
DISPLAY 0.723404 (-3500 3650);
PAINT MONO (-3500 3650);
DISPLAY INVISIBLE (-3500 3650);
FORCEPROP 1 LAST BODY_TYPE PLUMBING
J 0
(-3500 3700);
DISPLAY 0.872340 (-3500 3700);
PAINT GREEN (-3500 3700);
DISPLAY INVISIBLE (-3500 3700);
FORCEPROP 1 LAST HDL_TAP TRUE
J 0
(-3175 3525);
DISPLAY 0.872340 (-3175 3525);
DISPLAY INVISIBLE (-3175 3525);
FORCEPROP 1 LAST PATH I204
J 0
(-3502 3650);
DISPLAY 0.872340 (-3502 3650);
PAINT GREEN (-3502 3650);
DISPLAY INVISIBLE (-3502 3650);
FORCEADD TAP..1
(-3500 3600);
FORCEPROP 3 LASTPIN (-3550 3600) SIG_NAME M_C_CPU0_SB_DQ<10>
J 0
(-3540 3610);
DISPLAY 0.659574 (-3540 3610);
PAINT MONO (-3540 3610);
DISPLAY INVISIBLE (-3540 3610);
FORCEPROP 1 LASTPIN (-3550 3600) BN 10
J 0
(-3562 3608);
DISPLAY 0.489362 (-3562 3608);
PAINT GREEN (-3562 3608);
FORCEPROP 2 LAST CDS_LIB mstr_standard
J 0
(-3500 3600);
DISPLAY 0.723404 (-3500 3600);
PAINT MONO (-3500 3600);
DISPLAY INVISIBLE (-3500 3600);
FORCEPROP 1 LAST BODY_TYPE PLUMBING
J 0
(-3500 3650);
DISPLAY 0.872340 (-3500 3650);
PAINT GREEN (-3500 3650);
DISPLAY INVISIBLE (-3500 3650);
FORCEPROP 1 LAST HDL_TAP TRUE
J 0
(-3175 3475);
DISPLAY 0.872340 (-3175 3475);
DISPLAY INVISIBLE (-3175 3475);
FORCEPROP 1 LAST PATH I205
J 0
(-3502 3600);
DISPLAY 0.872340 (-3502 3600);
PAINT GREEN (-3502 3600);
DISPLAY INVISIBLE (-3502 3600);
FORCEADD TAP..1
(-3500 3550);
FORCEPROP 3 LASTPIN (-3550 3550) SIG_NAME M_C_CPU0_SB_DQ<11>
J 0
(-3540 3560);
DISPLAY 0.659574 (-3540 3560);
PAINT MONO (-3540 3560);
DISPLAY INVISIBLE (-3540 3560);
FORCEPROP 1 LASTPIN (-3550 3550) BN 11
J 0
(-3562 3558);
DISPLAY 0.489362 (-3562 3558);
PAINT GREEN (-3562 3558);
FORCEPROP 2 LAST CDS_LIB mstr_standard
J 0
(-3500 3550);
DISPLAY 0.723404 (-3500 3550);
PAINT MONO (-3500 3550);
DISPLAY INVISIBLE (-3500 3550);
FORCEPROP 1 LAST BODY_TYPE PLUMBING
J 0
(-3500 3600);
DISPLAY 0.872340 (-3500 3600);
PAINT GREEN (-3500 3600);
DISPLAY INVISIBLE (-3500 3600);
FORCEPROP 1 LAST HDL_TAP TRUE
J 0
(-3175 3425);
DISPLAY 0.872340 (-3175 3425);
DISPLAY INVISIBLE (-3175 3425);
FORCEPROP 1 LAST PATH I206
J 0
(-3502 3550);
DISPLAY 0.872340 (-3502 3550);
PAINT GREEN (-3502 3550);
DISPLAY INVISIBLE (-3502 3550);
FORCEADD TAP..1
(-3500 3500);
FORCEPROP 3 LASTPIN (-3550 3500) SIG_NAME M_C_CPU0_SB_DQ<12>
J 0
(-3540 3510);
DISPLAY 0.659574 (-3540 3510);
PAINT MONO (-3540 3510);
DISPLAY INVISIBLE (-3540 3510);
FORCEPROP 1 LASTPIN (-3550 3500) BN 12
J 0
(-3562 3508);
DISPLAY 0.489362 (-3562 3508);
PAINT GREEN (-3562 3508);
FORCEPROP 2 LAST CDS_LIB mstr_standard
J 0
(-3500 3500);
DISPLAY 0.723404 (-3500 3500);
PAINT MONO (-3500 3500);
DISPLAY INVISIBLE (-3500 3500);
FORCEPROP 1 LAST BODY_TYPE PLUMBING
J 0
(-3500 3550);
DISPLAY 0.872340 (-3500 3550);
PAINT GREEN (-3500 3550);
DISPLAY INVISIBLE (-3500 3550);
FORCEPROP 1 LAST HDL_TAP TRUE
J 0
(-3175 3375);
DISPLAY 0.872340 (-3175 3375);
DISPLAY INVISIBLE (-3175 3375);
FORCEPROP 1 LAST PATH I207
J 0
(-3502 3500);
DISPLAY 0.872340 (-3502 3500);
PAINT GREEN (-3502 3500);
DISPLAY INVISIBLE (-3502 3500);
FORCEADD TAP..1
(-3500 3400);
FORCEPROP 3 LASTPIN (-3550 3400) SIG_NAME M_C_CPU0_SB_DQ<14>
J 0
(-3540 3410);
DISPLAY 0.659574 (-3540 3410);
PAINT MONO (-3540 3410);
DISPLAY INVISIBLE (-3540 3410);
FORCEPROP 1 LASTPIN (-3550 3400) BN 14
J 0
(-3562 3408);
DISPLAY 0.489362 (-3562 3408);
PAINT GREEN (-3562 3408);
FORCEPROP 2 LAST CDS_LIB mstr_standard
J 0
(-3500 3400);
DISPLAY 0.723404 (-3500 3400);
PAINT MONO (-3500 3400);
DISPLAY INVISIBLE (-3500 3400);
FORCEPROP 1 LAST BODY_TYPE PLUMBING
J 0
(-3500 3450);
DISPLAY 0.872340 (-3500 3450);
PAINT GREEN (-3500 3450);
DISPLAY INVISIBLE (-3500 3450);
FORCEPROP 1 LAST HDL_TAP TRUE
J 0
(-3175 3275);
DISPLAY 0.872340 (-3175 3275);
DISPLAY INVISIBLE (-3175 3275);
FORCEPROP 1 LAST PATH I208
J 0
(-3502 3400);
DISPLAY 0.872340 (-3502 3400);
PAINT GREEN (-3502 3400);
DISPLAY INVISIBLE (-3502 3400);
FORCEADD TAP..1
(-3500 3350);
FORCEPROP 3 LASTPIN (-3550 3350) SIG_NAME M_C_CPU0_SB_DQ<15>
J 0
(-3540 3360);
DISPLAY 0.659574 (-3540 3360);
PAINT MONO (-3540 3360);
DISPLAY INVISIBLE (-3540 3360);
FORCEPROP 1 LASTPIN (-3550 3350) BN 15
J 0
(-3562 3358);
DISPLAY 0.489362 (-3562 3358);
PAINT GREEN (-3562 3358);
FORCEPROP 2 LAST CDS_LIB mstr_standard
J 0
(-3500 3350);
DISPLAY 0.723404 (-3500 3350);
PAINT MONO (-3500 3350);
DISPLAY INVISIBLE (-3500 3350);
FORCEPROP 1 LAST BODY_TYPE PLUMBING
J 0
(-3500 3400);
DISPLAY 0.872340 (-3500 3400);
PAINT GREEN (-3500 3400);
DISPLAY INVISIBLE (-3500 3400);
FORCEPROP 1 LAST HDL_TAP TRUE
J 0
(-3175 3225);
DISPLAY 0.872340 (-3175 3225);
DISPLAY INVISIBLE (-3175 3225);
FORCEPROP 1 LAST PATH I209
J 0
(-3502 3350);
DISPLAY 0.872340 (-3502 3350);
PAINT GREEN (-3502 3350);
DISPLAY INVISIBLE (-3502 3350);
FORCEADD TAP..1
(-3500 3450);
FORCEPROP 3 LASTPIN (-3550 3450) SIG_NAME M_C_CPU0_SB_DQ<13>
J 0
(-3540 3460);
DISPLAY 0.659574 (-3540 3460);
PAINT MONO (-3540 3460);
DISPLAY INVISIBLE (-3540 3460);
FORCEPROP 1 LASTPIN (-3550 3450) BN 13
J 0
(-3562 3458);
DISPLAY 0.489362 (-3562 3458);
PAINT GREEN (-3562 3458);
FORCEPROP 2 LAST CDS_LIB mstr_standard
J 0
(-3500 3450);
DISPLAY 0.723404 (-3500 3450);
PAINT MONO (-3500 3450);
DISPLAY INVISIBLE (-3500 3450);
FORCEPROP 1 LAST BODY_TYPE PLUMBING
J 0
(-3500 3500);
DISPLAY 0.872340 (-3500 3500);
PAINT GREEN (-3500 3500);
DISPLAY INVISIBLE (-3500 3500);
FORCEPROP 1 LAST HDL_TAP TRUE
J 0
(-3175 3325);
DISPLAY 0.872340 (-3175 3325);
DISPLAY INVISIBLE (-3175 3325);
FORCEPROP 1 LAST PATH I210
J 0
(-3502 3450);
DISPLAY 0.872340 (-3502 3450);
PAINT GREEN (-3502 3450);
DISPLAY INVISIBLE (-3502 3450);
FORCEADD TAP..1
(-3500 3250);
FORCEPROP 3 LASTPIN (-3550 3250) SIG_NAME M_C_CPU0_SB_DQ<16>
J 0
(-3540 3260);
DISPLAY 0.659574 (-3540 3260);
PAINT MONO (-3540 3260);
DISPLAY INVISIBLE (-3540 3260);
FORCEPROP 1 LASTPIN (-3550 3250) BN 16
J 0
(-3562 3258);
DISPLAY 0.489362 (-3562 3258);
PAINT GREEN (-3562 3258);
FORCEPROP 2 LAST CDS_LIB mstr_standard
J 0
(-3500 3250);
DISPLAY 0.723404 (-3500 3250);
PAINT MONO (-3500 3250);
DISPLAY INVISIBLE (-3500 3250);
FORCEPROP 1 LAST BODY_TYPE PLUMBING
J 0
(-3500 3300);
DISPLAY 0.872340 (-3500 3300);
PAINT GREEN (-3500 3300);
DISPLAY INVISIBLE (-3500 3300);
FORCEPROP 1 LAST HDL_TAP TRUE
J 0
(-3175 3125);
DISPLAY 0.872340 (-3175 3125);
DISPLAY INVISIBLE (-3175 3125);
FORCEPROP 1 LAST PATH I211
J 0
(-3502 3250);
DISPLAY 0.872340 (-3502 3250);
PAINT GREEN (-3502 3250);
DISPLAY INVISIBLE (-3502 3250);
FORCEADD TAP..1
(-3500 3200);
FORCEPROP 3 LASTPIN (-3550 3200) SIG_NAME M_C_CPU0_SB_DQ<17>
J 0
(-3540 3210);
DISPLAY 0.659574 (-3540 3210);
PAINT MONO (-3540 3210);
DISPLAY INVISIBLE (-3540 3210);
FORCEPROP 1 LASTPIN (-3550 3200) BN 17
J 0
(-3562 3208);
DISPLAY 0.489362 (-3562 3208);
PAINT GREEN (-3562 3208);
FORCEPROP 2 LAST CDS_LIB mstr_standard
J 0
(-3500 3200);
DISPLAY 0.723404 (-3500 3200);
PAINT MONO (-3500 3200);
DISPLAY INVISIBLE (-3500 3200);
FORCEPROP 1 LAST BODY_TYPE PLUMBING
J 0
(-3500 3250);
DISPLAY 0.872340 (-3500 3250);
PAINT GREEN (-3500 3250);
DISPLAY INVISIBLE (-3500 3250);
FORCEPROP 1 LAST HDL_TAP TRUE
J 0
(-3175 3075);
DISPLAY 0.872340 (-3175 3075);
DISPLAY INVISIBLE (-3175 3075);
FORCEPROP 1 LAST PATH I212
J 0
(-3502 3200);
DISPLAY 0.872340 (-3502 3200);
PAINT GREEN (-3502 3200);
DISPLAY INVISIBLE (-3502 3200);
FORCEADD TAP..1
(-3500 3150);
FORCEPROP 3 LASTPIN (-3550 3150) SIG_NAME M_C_CPU0_SB_DQ<18>
J 0
(-3540 3160);
DISPLAY 0.659574 (-3540 3160);
PAINT MONO (-3540 3160);
DISPLAY INVISIBLE (-3540 3160);
FORCEPROP 1 LASTPIN (-3550 3150) BN 18
J 0
(-3562 3158);
DISPLAY 0.489362 (-3562 3158);
PAINT GREEN (-3562 3158);
FORCEPROP 2 LAST CDS_LIB mstr_standard
J 0
(-3500 3150);
DISPLAY 0.723404 (-3500 3150);
PAINT MONO (-3500 3150);
DISPLAY INVISIBLE (-3500 3150);
FORCEPROP 1 LAST BODY_TYPE PLUMBING
J 0
(-3500 3200);
DISPLAY 0.872340 (-3500 3200);
PAINT GREEN (-3500 3200);
DISPLAY INVISIBLE (-3500 3200);
FORCEPROP 1 LAST HDL_TAP TRUE
J 0
(-3175 3025);
DISPLAY 0.872340 (-3175 3025);
DISPLAY INVISIBLE (-3175 3025);
FORCEPROP 1 LAST PATH I213
J 0
(-3502 3150);
DISPLAY 0.872340 (-3502 3150);
PAINT GREEN (-3502 3150);
DISPLAY INVISIBLE (-3502 3150);
FORCEADD TAP..1
(-3500 3100);
FORCEPROP 3 LASTPIN (-3550 3100) SIG_NAME M_C_CPU0_SB_DQ<19>
J 0
(-3540 3110);
DISPLAY 0.659574 (-3540 3110);
PAINT MONO (-3540 3110);
DISPLAY INVISIBLE (-3540 3110);
FORCEPROP 1 LASTPIN (-3550 3100) BN 19
J 0
(-3562 3108);
DISPLAY 0.489362 (-3562 3108);
PAINT GREEN (-3562 3108);
FORCEPROP 2 LAST CDS_LIB mstr_standard
J 0
(-3500 3100);
DISPLAY 0.723404 (-3500 3100);
PAINT MONO (-3500 3100);
DISPLAY INVISIBLE (-3500 3100);
FORCEPROP 1 LAST BODY_TYPE PLUMBING
J 0
(-3500 3150);
DISPLAY 0.872340 (-3500 3150);
PAINT GREEN (-3500 3150);
DISPLAY INVISIBLE (-3500 3150);
FORCEPROP 1 LAST HDL_TAP TRUE
J 0
(-3175 2975);
DISPLAY 0.872340 (-3175 2975);
DISPLAY INVISIBLE (-3175 2975);
FORCEPROP 1 LAST PATH I214
J 0
(-3502 3100);
DISPLAY 0.872340 (-3502 3100);
PAINT GREEN (-3502 3100);
DISPLAY INVISIBLE (-3502 3100);
FORCEADD TAP..1
(-3500 2950);
FORCEPROP 3 LASTPIN (-3550 2950) SIG_NAME M_C_CPU0_SB_DQ<22>
J 0
(-3540 2960);
DISPLAY 0.659574 (-3540 2960);
PAINT MONO (-3540 2960);
DISPLAY INVISIBLE (-3540 2960);
FORCEPROP 1 LASTPIN (-3550 2950) BN 22
J 0
(-3562 2958);
DISPLAY 0.489362 (-3562 2958);
PAINT GREEN (-3562 2958);
FORCEPROP 2 LAST CDS_LIB mstr_standard
J 0
(-3500 2950);
DISPLAY 0.723404 (-3500 2950);
PAINT MONO (-3500 2950);
DISPLAY INVISIBLE (-3500 2950);
FORCEPROP 1 LAST BODY_TYPE PLUMBING
J 0
(-3500 3000);
DISPLAY 0.872340 (-3500 3000);
PAINT GREEN (-3500 3000);
DISPLAY INVISIBLE (-3500 3000);
FORCEPROP 1 LAST HDL_TAP TRUE
J 0
(-3175 2825);
DISPLAY 0.872340 (-3175 2825);
DISPLAY INVISIBLE (-3175 2825);
FORCEPROP 1 LAST PATH I215
J 0
(-3502 2950);
DISPLAY 0.872340 (-3502 2950);
PAINT GREEN (-3502 2950);
DISPLAY INVISIBLE (-3502 2950);
FORCEADD TAP..1
(-3500 3050);
FORCEPROP 3 LASTPIN (-3550 3050) SIG_NAME M_C_CPU0_SB_DQ<20>
J 0
(-3540 3060);
DISPLAY 0.659574 (-3540 3060);
PAINT MONO (-3540 3060);
DISPLAY INVISIBLE (-3540 3060);
FORCEPROP 1 LASTPIN (-3550 3050) BN 20
J 0
(-3562 3058);
DISPLAY 0.489362 (-3562 3058);
PAINT GREEN (-3562 3058);
FORCEPROP 2 LAST CDS_LIB mstr_standard
J 0
(-3500 3050);
DISPLAY 0.723404 (-3500 3050);
PAINT MONO (-3500 3050);
DISPLAY INVISIBLE (-3500 3050);
FORCEPROP 1 LAST BODY_TYPE PLUMBING
J 0
(-3500 3100);
DISPLAY 0.872340 (-3500 3100);
PAINT GREEN (-3500 3100);
DISPLAY INVISIBLE (-3500 3100);
FORCEPROP 1 LAST HDL_TAP TRUE
J 0
(-3175 2925);
DISPLAY 0.872340 (-3175 2925);
DISPLAY INVISIBLE (-3175 2925);
FORCEPROP 1 LAST PATH I216
J 0
(-3502 3050);
DISPLAY 0.872340 (-3502 3050);
PAINT GREEN (-3502 3050);
DISPLAY INVISIBLE (-3502 3050);
FORCEADD TAP..1
(-3500 2900);
FORCEPROP 3 LASTPIN (-3550 2900) SIG_NAME M_C_CPU0_SB_DQ<23>
J 0
(-3540 2910);
DISPLAY 0.659574 (-3540 2910);
PAINT MONO (-3540 2910);
DISPLAY INVISIBLE (-3540 2910);
FORCEPROP 1 LASTPIN (-3550 2900) BN 23
J 0
(-3562 2908);
DISPLAY 0.489362 (-3562 2908);
PAINT GREEN (-3562 2908);
FORCEPROP 2 LAST CDS_LIB mstr_standard
J 0
(-3500 2900);
DISPLAY 0.723404 (-3500 2900);
PAINT MONO (-3500 2900);
DISPLAY INVISIBLE (-3500 2900);
FORCEPROP 1 LAST BODY_TYPE PLUMBING
J 0
(-3500 2950);
DISPLAY 0.872340 (-3500 2950);
PAINT GREEN (-3500 2950);
DISPLAY INVISIBLE (-3500 2950);
FORCEPROP 1 LAST HDL_TAP TRUE
J 0
(-3175 2775);
DISPLAY 0.872340 (-3175 2775);
DISPLAY INVISIBLE (-3175 2775);
FORCEPROP 1 LAST PATH I217
J 0
(-3502 2900);
DISPLAY 0.872340 (-3502 2900);
PAINT GREEN (-3502 2900);
DISPLAY INVISIBLE (-3502 2900);
FORCEADD TAP..1
(-3500 3000);
FORCEPROP 3 LASTPIN (-3550 3000) SIG_NAME M_C_CPU0_SB_DQ<21>
J 0
(-3540 3010);
DISPLAY 0.659574 (-3540 3010);
PAINT MONO (-3540 3010);
DISPLAY INVISIBLE (-3540 3010);
FORCEPROP 1 LASTPIN (-3550 3000) BN 21
J 0
(-3562 3008);
DISPLAY 0.489362 (-3562 3008);
PAINT GREEN (-3562 3008);
FORCEPROP 2 LAST CDS_LIB mstr_standard
J 0
(-3500 3000);
DISPLAY 0.723404 (-3500 3000);
PAINT MONO (-3500 3000);
DISPLAY INVISIBLE (-3500 3000);
FORCEPROP 1 LAST BODY_TYPE PLUMBING
J 0
(-3500 3050);
DISPLAY 0.872340 (-3500 3050);
PAINT GREEN (-3500 3050);
DISPLAY INVISIBLE (-3500 3050);
FORCEPROP 1 LAST HDL_TAP TRUE
J 0
(-3175 2875);
DISPLAY 0.872340 (-3175 2875);
DISPLAY INVISIBLE (-3175 2875);
FORCEPROP 1 LAST PATH I218
J 0
(-3502 3000);
DISPLAY 0.872340 (-3502 3000);
PAINT GREEN (-3502 3000);
DISPLAY INVISIBLE (-3502 3000);
FORCEADD TAP..1
(-3500 2800);
FORCEPROP 3 LASTPIN (-3550 2800) SIG_NAME M_C_CPU0_SB_DQ<24>
J 0
(-3540 2810);
DISPLAY 0.659574 (-3540 2810);
PAINT MONO (-3540 2810);
DISPLAY INVISIBLE (-3540 2810);
FORCEPROP 1 LASTPIN (-3550 2800) BN 24
J 0
(-3562 2808);
DISPLAY 0.489362 (-3562 2808);
PAINT GREEN (-3562 2808);
FORCEPROP 2 LAST CDS_LIB mstr_standard
J 0
(-3500 2800);
DISPLAY 0.723404 (-3500 2800);
PAINT MONO (-3500 2800);
DISPLAY INVISIBLE (-3500 2800);
FORCEPROP 1 LAST BODY_TYPE PLUMBING
J 0
(-3500 2850);
DISPLAY 0.872340 (-3500 2850);
PAINT GREEN (-3500 2850);
DISPLAY INVISIBLE (-3500 2850);
FORCEPROP 1 LAST HDL_TAP TRUE
J 0
(-3175 2675);
DISPLAY 0.872340 (-3175 2675);
DISPLAY INVISIBLE (-3175 2675);
FORCEPROP 1 LAST PATH I219
J 0
(-3502 2800);
DISPLAY 0.872340 (-3502 2800);
PAINT GREEN (-3502 2800);
DISPLAY INVISIBLE (-3502 2800);
FORCEADD TAP..1
(-3500 2700);
FORCEPROP 3 LASTPIN (-3550 2700) SIG_NAME M_C_CPU0_SB_DQ<26>
J 0
(-3540 2710);
DISPLAY 0.659574 (-3540 2710);
PAINT MONO (-3540 2710);
DISPLAY INVISIBLE (-3540 2710);
FORCEPROP 1 LASTPIN (-3550 2700) BN 26
J 0
(-3562 2708);
DISPLAY 0.489362 (-3562 2708);
PAINT GREEN (-3562 2708);
FORCEPROP 2 LAST CDS_LIB mstr_standard
J 0
(-3500 2700);
DISPLAY 0.723404 (-3500 2700);
PAINT MONO (-3500 2700);
DISPLAY INVISIBLE (-3500 2700);
FORCEPROP 1 LAST BODY_TYPE PLUMBING
J 0
(-3500 2750);
DISPLAY 0.872340 (-3500 2750);
PAINT GREEN (-3500 2750);
DISPLAY INVISIBLE (-3500 2750);
FORCEPROP 1 LAST HDL_TAP TRUE
J 0
(-3175 2575);
DISPLAY 0.872340 (-3175 2575);
DISPLAY INVISIBLE (-3175 2575);
FORCEPROP 1 LAST PATH I220
J 0
(-3502 2700);
DISPLAY 0.872340 (-3502 2700);
PAINT GREEN (-3502 2700);
DISPLAY INVISIBLE (-3502 2700);
FORCEADD TAP..1
(-3500 2750);
FORCEPROP 3 LASTPIN (-3550 2750) SIG_NAME M_C_CPU0_SB_DQ<25>
J 0
(-3540 2760);
DISPLAY 0.659574 (-3540 2760);
PAINT MONO (-3540 2760);
DISPLAY INVISIBLE (-3540 2760);
FORCEPROP 1 LASTPIN (-3550 2750) BN 25
J 0
(-3562 2758);
DISPLAY 0.489362 (-3562 2758);
PAINT GREEN (-3562 2758);
FORCEPROP 2 LAST CDS_LIB mstr_standard
J 0
(-3500 2750);
DISPLAY 0.723404 (-3500 2750);
PAINT MONO (-3500 2750);
DISPLAY INVISIBLE (-3500 2750);
FORCEPROP 1 LAST BODY_TYPE PLUMBING
J 0
(-3500 2800);
DISPLAY 0.872340 (-3500 2800);
PAINT GREEN (-3500 2800);
DISPLAY INVISIBLE (-3500 2800);
FORCEPROP 1 LAST HDL_TAP TRUE
J 0
(-3175 2625);
DISPLAY 0.872340 (-3175 2625);
DISPLAY INVISIBLE (-3175 2625);
FORCEPROP 1 LAST PATH I221
J 0
(-3502 2750);
DISPLAY 0.872340 (-3502 2750);
PAINT GREEN (-3502 2750);
DISPLAY INVISIBLE (-3502 2750);
FORCEADD TAP..1
(-3500 2650);
FORCEPROP 3 LASTPIN (-3550 2650) SIG_NAME M_C_CPU0_SB_DQ<27>
J 0
(-3540 2660);
DISPLAY 0.659574 (-3540 2660);
PAINT MONO (-3540 2660);
DISPLAY INVISIBLE (-3540 2660);
FORCEPROP 1 LASTPIN (-3550 2650) BN 27
J 0
(-3562 2658);
DISPLAY 0.489362 (-3562 2658);
PAINT GREEN (-3562 2658);
FORCEPROP 2 LAST CDS_LIB mstr_standard
J 0
(-3500 2650);
DISPLAY 0.723404 (-3500 2650);
PAINT MONO (-3500 2650);
DISPLAY INVISIBLE (-3500 2650);
FORCEPROP 1 LAST BODY_TYPE PLUMBING
J 0
(-3500 2700);
DISPLAY 0.872340 (-3500 2700);
PAINT GREEN (-3500 2700);
DISPLAY INVISIBLE (-3500 2700);
FORCEPROP 1 LAST HDL_TAP TRUE
J 0
(-3175 2525);
DISPLAY 0.872340 (-3175 2525);
DISPLAY INVISIBLE (-3175 2525);
FORCEPROP 1 LAST PATH I222
J 0
(-3502 2650);
DISPLAY 0.872340 (-3502 2650);
PAINT GREEN (-3502 2650);
DISPLAY INVISIBLE (-3502 2650);
FORCEADD TAP..1
(-3500 2600);
FORCEPROP 3 LASTPIN (-3550 2600) SIG_NAME M_C_CPU0_SB_DQ<28>
J 0
(-3540 2610);
DISPLAY 0.659574 (-3540 2610);
PAINT MONO (-3540 2610);
DISPLAY INVISIBLE (-3540 2610);
FORCEPROP 1 LASTPIN (-3550 2600) BN 28
J 0
(-3562 2608);
DISPLAY 0.489362 (-3562 2608);
PAINT GREEN (-3562 2608);
FORCEPROP 2 LAST CDS_LIB mstr_standard
J 0
(-3500 2600);
DISPLAY 0.723404 (-3500 2600);
PAINT MONO (-3500 2600);
DISPLAY INVISIBLE (-3500 2600);
FORCEPROP 1 LAST BODY_TYPE PLUMBING
J 0
(-3500 2650);
DISPLAY 0.872340 (-3500 2650);
PAINT GREEN (-3500 2650);
DISPLAY INVISIBLE (-3500 2650);
FORCEPROP 1 LAST HDL_TAP TRUE
J 0
(-3175 2475);
DISPLAY 0.872340 (-3175 2475);
DISPLAY INVISIBLE (-3175 2475);
FORCEPROP 1 LAST PATH I223
J 0
(-3502 2600);
DISPLAY 0.872340 (-3502 2600);
PAINT GREEN (-3502 2600);
DISPLAY INVISIBLE (-3502 2600);
FORCEADD TAP..1
(-3500 2550);
FORCEPROP 3 LASTPIN (-3550 2550) SIG_NAME M_C_CPU0_SB_DQ<29>
J 0
(-3540 2560);
DISPLAY 0.659574 (-3540 2560);
PAINT MONO (-3540 2560);
DISPLAY INVISIBLE (-3540 2560);
FORCEPROP 1 LASTPIN (-3550 2550) BN 29
J 0
(-3562 2558);
DISPLAY 0.489362 (-3562 2558);
PAINT GREEN (-3562 2558);
FORCEPROP 2 LAST CDS_LIB mstr_standard
J 0
(-3500 2550);
DISPLAY 0.723404 (-3500 2550);
PAINT MONO (-3500 2550);
DISPLAY INVISIBLE (-3500 2550);
FORCEPROP 1 LAST BODY_TYPE PLUMBING
J 0
(-3500 2600);
DISPLAY 0.872340 (-3500 2600);
PAINT GREEN (-3500 2600);
DISPLAY INVISIBLE (-3500 2600);
FORCEPROP 1 LAST HDL_TAP TRUE
J 0
(-3175 2425);
DISPLAY 0.872340 (-3175 2425);
DISPLAY INVISIBLE (-3175 2425);
FORCEPROP 1 LAST PATH I224
J 0
(-3502 2550);
DISPLAY 0.872340 (-3502 2550);
PAINT GREEN (-3502 2550);
DISPLAY INVISIBLE (-3502 2550);
FORCEADD TAP..1
(-3500 2500);
FORCEPROP 3 LASTPIN (-3550 2500) SIG_NAME M_C_CPU0_SB_DQ<30>
J 0
(-3540 2510);
DISPLAY 0.659574 (-3540 2510);
PAINT MONO (-3540 2510);
DISPLAY INVISIBLE (-3540 2510);
FORCEPROP 1 LASTPIN (-3550 2500) BN 30
J 0
(-3562 2508);
DISPLAY 0.489362 (-3562 2508);
PAINT GREEN (-3562 2508);
FORCEPROP 2 LAST CDS_LIB mstr_standard
J 0
(-3500 2500);
DISPLAY 0.723404 (-3500 2500);
PAINT MONO (-3500 2500);
DISPLAY INVISIBLE (-3500 2500);
FORCEPROP 1 LAST BODY_TYPE PLUMBING
J 0
(-3500 2550);
DISPLAY 0.872340 (-3500 2550);
PAINT GREEN (-3500 2550);
DISPLAY INVISIBLE (-3500 2550);
FORCEPROP 1 LAST HDL_TAP TRUE
J 0
(-3175 2375);
DISPLAY 0.872340 (-3175 2375);
DISPLAY INVISIBLE (-3175 2375);
FORCEPROP 1 LAST PATH I225
J 0
(-3502 2500);
DISPLAY 0.872340 (-3502 2500);
PAINT GREEN (-3502 2500);
DISPLAY INVISIBLE (-3502 2500);
FORCEADD TAP..1
(-3500 2450);
FORCEPROP 3 LASTPIN (-3550 2450) SIG_NAME M_C_CPU0_SB_DQ<31>
J 0
(-3540 2460);
DISPLAY 0.659574 (-3540 2460);
PAINT MONO (-3540 2460);
DISPLAY INVISIBLE (-3540 2460);
FORCEPROP 1 LASTPIN (-3550 2450) BN 31
J 0
(-3562 2458);
DISPLAY 0.489362 (-3562 2458);
PAINT GREEN (-3562 2458);
FORCEPROP 2 LAST CDS_LIB mstr_standard
J 0
(-3500 2450);
DISPLAY 0.723404 (-3500 2450);
PAINT MONO (-3500 2450);
DISPLAY INVISIBLE (-3500 2450);
FORCEPROP 1 LAST BODY_TYPE PLUMBING
J 0
(-3500 2500);
DISPLAY 0.872340 (-3500 2500);
PAINT GREEN (-3500 2500);
DISPLAY INVISIBLE (-3500 2500);
FORCEPROP 1 LAST HDL_TAP TRUE
J 0
(-3175 2325);
DISPLAY 0.872340 (-3175 2325);
DISPLAY INVISIBLE (-3175 2325);
FORCEPROP 1 LAST PATH I226
J 0
(-3502 2450);
DISPLAY 0.872340 (-3502 2450);
PAINT GREEN (-3502 2450);
DISPLAY INVISIBLE (-3502 2450);
FORCEADD TAP..1
(-3500 2350);
FORCEPROP 3 LASTPIN (-3550 2350) SIG_NAME M_C_CPU0_SA_CB<0>
J 0
(-3540 2360);
DISPLAY 0.659574 (-3540 2360);
PAINT MONO (-3540 2360);
DISPLAY INVISIBLE (-3540 2360);
FORCEPROP 1 LASTPIN (-3550 2350) BN 0
J 0
(-3562 2358);
DISPLAY 0.489362 (-3562 2358);
PAINT GREEN (-3562 2358);
FORCEPROP 2 LAST CDS_LIB mstr_standard
J 2
(-3500 2350);
DISPLAY 0.723404 (-3500 2350);
PAINT MONO (-3500 2350);
DISPLAY INVISIBLE (-3500 2350);
FORCEPROP 1 LAST BODY_TYPE PLUMBING
J 0
(-3500 2400);
DISPLAY 0.872340 (-3500 2400);
PAINT GREEN (-3500 2400);
DISPLAY INVISIBLE (-3500 2400);
FORCEPROP 1 LAST HDL_TAP TRUE
J 0
(-3175 2225);
DISPLAY 0.872340 (-3175 2225);
DISPLAY INVISIBLE (-3175 2225);
FORCEPROP 1 LAST PATH I227
J 0
(-3502 2350);
DISPLAY 0.872340 (-3502 2350);
PAINT GREEN (-3502 2350);
DISPLAY INVISIBLE (-3502 2350);
FORCEADD TAP..1
(-3500 2300);
FORCEPROP 3 LASTPIN (-3550 2300) SIG_NAME M_C_CPU0_SA_CB<1>
J 0
(-3540 2310);
DISPLAY 0.659574 (-3540 2310);
PAINT MONO (-3540 2310);
DISPLAY INVISIBLE (-3540 2310);
FORCEPROP 1 LASTPIN (-3550 2300) BN 1
J 0
(-3562 2308);
DISPLAY 0.489362 (-3562 2308);
PAINT GREEN (-3562 2308);
FORCEPROP 2 LAST CDS_LIB mstr_standard
J 2
(-3500 2300);
DISPLAY 0.723404 (-3500 2300);
PAINT MONO (-3500 2300);
DISPLAY INVISIBLE (-3500 2300);
FORCEPROP 1 LAST BODY_TYPE PLUMBING
J 0
(-3500 2350);
DISPLAY 0.872340 (-3500 2350);
PAINT GREEN (-3500 2350);
DISPLAY INVISIBLE (-3500 2350);
FORCEPROP 1 LAST HDL_TAP TRUE
J 0
(-3175 2175);
DISPLAY 0.872340 (-3175 2175);
DISPLAY INVISIBLE (-3175 2175);
FORCEPROP 1 LAST PATH I228
J 0
(-3502 2300);
DISPLAY 0.872340 (-3502 2300);
PAINT GREEN (-3502 2300);
DISPLAY INVISIBLE (-3502 2300);
FORCEADD TAP..1
(-3500 2250);
FORCEPROP 3 LASTPIN (-3550 2250) SIG_NAME M_C_CPU0_SA_CB<2>
J 0
(-3540 2260);
DISPLAY 0.659574 (-3540 2260);
PAINT MONO (-3540 2260);
DISPLAY INVISIBLE (-3540 2260);
FORCEPROP 1 LASTPIN (-3550 2250) BN 2
J 0
(-3562 2258);
DISPLAY 0.489362 (-3562 2258);
PAINT GREEN (-3562 2258);
FORCEPROP 2 LAST CDS_LIB mstr_standard
J 2
(-3500 2250);
DISPLAY 0.723404 (-3500 2250);
PAINT MONO (-3500 2250);
DISPLAY INVISIBLE (-3500 2250);
FORCEPROP 1 LAST BODY_TYPE PLUMBING
J 0
(-3500 2300);
DISPLAY 0.872340 (-3500 2300);
PAINT GREEN (-3500 2300);
DISPLAY INVISIBLE (-3500 2300);
FORCEPROP 1 LAST HDL_TAP TRUE
J 0
(-3175 2125);
DISPLAY 0.872340 (-3175 2125);
DISPLAY INVISIBLE (-3175 2125);
FORCEPROP 1 LAST PATH I229
J 0
(-3502 2250);
DISPLAY 0.872340 (-3502 2250);
PAINT GREEN (-3502 2250);
DISPLAY INVISIBLE (-3502 2250);
FORCEADD TAP..1
(-3500 2200);
FORCEPROP 3 LASTPIN (-3550 2200) SIG_NAME M_C_CPU0_SA_CB<3>
J 0
(-3540 2210);
DISPLAY 0.659574 (-3540 2210);
PAINT MONO (-3540 2210);
DISPLAY INVISIBLE (-3540 2210);
FORCEPROP 1 LASTPIN (-3550 2200) BN 3
J 0
(-3562 2208);
DISPLAY 0.489362 (-3562 2208);
PAINT GREEN (-3562 2208);
FORCEPROP 2 LAST CDS_LIB mstr_standard
J 2
(-3500 2200);
DISPLAY 0.723404 (-3500 2200);
PAINT MONO (-3500 2200);
DISPLAY INVISIBLE (-3500 2200);
FORCEPROP 1 LAST BODY_TYPE PLUMBING
J 0
(-3500 2250);
DISPLAY 0.872340 (-3500 2250);
PAINT GREEN (-3500 2250);
DISPLAY INVISIBLE (-3500 2250);
FORCEPROP 1 LAST HDL_TAP TRUE
J 0
(-3175 2075);
DISPLAY 0.872340 (-3175 2075);
DISPLAY INVISIBLE (-3175 2075);
FORCEPROP 1 LAST PATH I230
J 0
(-3502 2200);
DISPLAY 0.872340 (-3502 2200);
PAINT GREEN (-3502 2200);
DISPLAY INVISIBLE (-3502 2200);
FORCEADD TAP..1
(-3500 2150);
FORCEPROP 3 LASTPIN (-3550 2150) SIG_NAME M_C_CPU0_SA_CB<4>
J 0
(-3540 2160);
DISPLAY 0.659574 (-3540 2160);
PAINT MONO (-3540 2160);
DISPLAY INVISIBLE (-3540 2160);
FORCEPROP 1 LASTPIN (-3550 2150) BN 4
J 0
(-3562 2158);
DISPLAY 0.489362 (-3562 2158);
PAINT GREEN (-3562 2158);
FORCEPROP 2 LAST CDS_LIB mstr_standard
J 2
(-3500 2150);
DISPLAY 0.723404 (-3500 2150);
PAINT MONO (-3500 2150);
DISPLAY INVISIBLE (-3500 2150);
FORCEPROP 1 LAST BODY_TYPE PLUMBING
J 0
(-3500 2200);
DISPLAY 0.872340 (-3500 2200);
PAINT GREEN (-3500 2200);
DISPLAY INVISIBLE (-3500 2200);
FORCEPROP 1 LAST HDL_TAP TRUE
J 0
(-3175 2025);
DISPLAY 0.872340 (-3175 2025);
DISPLAY INVISIBLE (-3175 2025);
FORCEPROP 1 LAST PATH I231
J 0
(-3502 2150);
DISPLAY 0.872340 (-3502 2150);
PAINT GREEN (-3502 2150);
DISPLAY INVISIBLE (-3502 2150);
FORCEADD TAP..1
(-3500 2100);
FORCEPROP 3 LASTPIN (-3550 2100) SIG_NAME M_C_CPU0_SA_CB<5>
J 0
(-3540 2110);
DISPLAY 0.659574 (-3540 2110);
PAINT MONO (-3540 2110);
DISPLAY INVISIBLE (-3540 2110);
FORCEPROP 1 LASTPIN (-3550 2100) BN 5
J 0
(-3562 2108);
DISPLAY 0.489362 (-3562 2108);
PAINT GREEN (-3562 2108);
FORCEPROP 2 LAST CDS_LIB mstr_standard
J 2
(-3500 2100);
DISPLAY 0.723404 (-3500 2100);
PAINT MONO (-3500 2100);
DISPLAY INVISIBLE (-3500 2100);
FORCEPROP 1 LAST BODY_TYPE PLUMBING
J 0
(-3500 2150);
DISPLAY 0.872340 (-3500 2150);
PAINT GREEN (-3500 2150);
DISPLAY INVISIBLE (-3500 2150);
FORCEPROP 1 LAST HDL_TAP TRUE
J 0
(-3175 1975);
DISPLAY 0.872340 (-3175 1975);
DISPLAY INVISIBLE (-3175 1975);
FORCEPROP 1 LAST PATH I232
J 0
(-3502 2100);
DISPLAY 0.872340 (-3502 2100);
PAINT GREEN (-3502 2100);
DISPLAY INVISIBLE (-3502 2100);
FORCEADD TAP..1
(-3500 2050);
FORCEPROP 3 LASTPIN (-3550 2050) SIG_NAME M_C_CPU0_SA_CB<6>
J 0
(-3540 2060);
DISPLAY 0.659574 (-3540 2060);
PAINT MONO (-3540 2060);
DISPLAY INVISIBLE (-3540 2060);
FORCEPROP 1 LASTPIN (-3550 2050) BN 6
J 0
(-3562 2058);
DISPLAY 0.489362 (-3562 2058);
PAINT GREEN (-3562 2058);
FORCEPROP 2 LAST CDS_LIB mstr_standard
J 2
(-3500 2050);
DISPLAY 0.723404 (-3500 2050);
PAINT MONO (-3500 2050);
DISPLAY INVISIBLE (-3500 2050);
FORCEPROP 1 LAST BODY_TYPE PLUMBING
J 0
(-3500 2100);
DISPLAY 0.872340 (-3500 2100);
PAINT GREEN (-3500 2100);
DISPLAY INVISIBLE (-3500 2100);
FORCEPROP 1 LAST HDL_TAP TRUE
J 0
(-3175 1925);
DISPLAY 0.872340 (-3175 1925);
DISPLAY INVISIBLE (-3175 1925);
FORCEPROP 1 LAST PATH I233
J 0
(-3502 2050);
DISPLAY 0.872340 (-3502 2050);
PAINT GREEN (-3502 2050);
DISPLAY INVISIBLE (-3502 2050);
FORCEADD OFFPAGE..6
R 2
(-2900 1950);
FORCEPROP 2 LAST $XR0 87 
J 0
(-2686 1950);
DISPLAY 0.638298 (-2686 1950);
PAINT MONO (-2686 1950);
FORCEPROP 2 LAST PATH I234
J 0
(-2675 2000);
DISPLAY 1.021277 (-2675 2000);
DISPLAY INVISIBLE (-2675 2000);
FORCEPROP 1 LAST COMMENT_BODY TRUE
J 2
(-3000 1875);
DISPLAY 0.872340 (-3000 1875);
PAINT GREEN (-3000 1875);
DISPLAY INVISIBLE (-3000 1875);
FORCEPROP 1 LAST OFFPAGE TRUE
J 2
(-3225 1825);
DISPLAY 0.872340 (-3225 1825);
PAINT GREEN (-3225 1825);
DISPLAY INVISIBLE (-3225 1825);
FORCEPROP 2 LAST CDS_LIB mstr_standard
J 2
(-2900 1950);
DISPLAY 0.723404 (-2900 1950);
PAINT MONO (-2900 1950);
DISPLAY INVISIBLE (-2900 1950);
FORCEADD TAP..1
(-3500 2000);
FORCEPROP 3 LASTPIN (-3550 2000) SIG_NAME M_C_CPU0_SA_CB<7>
J 0
(-3540 2010);
DISPLAY 0.659574 (-3540 2010);
PAINT MONO (-3540 2010);
DISPLAY INVISIBLE (-3540 2010);
FORCEPROP 1 LASTPIN (-3550 2000) BN 7
J 0
(-3562 2008);
DISPLAY 0.489362 (-3562 2008);
PAINT GREEN (-3562 2008);
FORCEPROP 2 LAST CDS_LIB mstr_standard
J 2
(-3500 2000);
DISPLAY 0.723404 (-3500 2000);
PAINT MONO (-3500 2000);
DISPLAY INVISIBLE (-3500 2000);
FORCEPROP 1 LAST BODY_TYPE PLUMBING
J 0
(-3500 2050);
DISPLAY 0.872340 (-3500 2050);
PAINT GREEN (-3500 2050);
DISPLAY INVISIBLE (-3500 2050);
FORCEPROP 1 LAST HDL_TAP TRUE
J 0
(-3175 1875);
DISPLAY 0.872340 (-3175 1875);
DISPLAY INVISIBLE (-3175 1875);
FORCEPROP 1 LAST PATH I235
J 0
(-3502 2000);
DISPLAY 0.872340 (-3502 2000);
PAINT GREEN (-3502 2000);
DISPLAY INVISIBLE (-3502 2000);
FORCEADD TAP..1
(-3500 1900);
FORCEPROP 3 LASTPIN (-3550 1900) SIG_NAME M_C_CPU0_SB_CB<0>
J 0
(-3540 1910);
DISPLAY 0.659574 (-3540 1910);
PAINT MONO (-3540 1910);
DISPLAY INVISIBLE (-3540 1910);
FORCEPROP 1 LASTPIN (-3550 1900) BN 0
J 0
(-3562 1908);
DISPLAY 0.489362 (-3562 1908);
PAINT GREEN (-3562 1908);
FORCEPROP 2 LAST CDS_LIB mstr_standard
J 2
(-3500 1900);
DISPLAY 0.723404 (-3500 1900);
PAINT MONO (-3500 1900);
DISPLAY INVISIBLE (-3500 1900);
FORCEPROP 1 LAST BODY_TYPE PLUMBING
J 0
(-3500 1950);
DISPLAY 0.872340 (-3500 1950);
PAINT GREEN (-3500 1950);
DISPLAY INVISIBLE (-3500 1950);
FORCEPROP 1 LAST HDL_TAP TRUE
J 0
(-3175 1775);
DISPLAY 0.872340 (-3175 1775);
DISPLAY INVISIBLE (-3175 1775);
FORCEPROP 1 LAST PATH I236
J 0
(-3502 1900);
DISPLAY 0.872340 (-3502 1900);
PAINT GREEN (-3502 1900);
DISPLAY INVISIBLE (-3502 1900);
FORCEADD TAP..1
(-3500 1850);
FORCEPROP 3 LASTPIN (-3550 1850) SIG_NAME M_C_CPU0_SB_CB<1>
J 0
(-3540 1860);
DISPLAY 0.659574 (-3540 1860);
PAINT MONO (-3540 1860);
DISPLAY INVISIBLE (-3540 1860);
FORCEPROP 1 LASTPIN (-3550 1850) BN 1
J 0
(-3562 1858);
DISPLAY 0.489362 (-3562 1858);
PAINT GREEN (-3562 1858);
FORCEPROP 2 LAST CDS_LIB mstr_standard
J 2
(-3500 1850);
DISPLAY 0.723404 (-3500 1850);
PAINT MONO (-3500 1850);
DISPLAY INVISIBLE (-3500 1850);
FORCEPROP 1 LAST BODY_TYPE PLUMBING
J 0
(-3500 1900);
DISPLAY 0.872340 (-3500 1900);
PAINT GREEN (-3500 1900);
DISPLAY INVISIBLE (-3500 1900);
FORCEPROP 1 LAST HDL_TAP TRUE
J 0
(-3175 1725);
DISPLAY 0.872340 (-3175 1725);
DISPLAY INVISIBLE (-3175 1725);
FORCEPROP 1 LAST PATH I237
J 0
(-3502 1850);
DISPLAY 0.872340 (-3502 1850);
PAINT GREEN (-3502 1850);
DISPLAY INVISIBLE (-3502 1850);
FORCEADD TAP..1
(-3500 1800);
FORCEPROP 3 LASTPIN (-3550 1800) SIG_NAME M_C_CPU0_SB_CB<2>
J 0
(-3540 1810);
DISPLAY 0.659574 (-3540 1810);
PAINT MONO (-3540 1810);
DISPLAY INVISIBLE (-3540 1810);
FORCEPROP 1 LASTPIN (-3550 1800) BN 2
J 0
(-3562 1808);
DISPLAY 0.489362 (-3562 1808);
PAINT GREEN (-3562 1808);
FORCEPROP 2 LAST CDS_LIB mstr_standard
J 2
(-3500 1800);
DISPLAY 0.723404 (-3500 1800);
PAINT MONO (-3500 1800);
DISPLAY INVISIBLE (-3500 1800);
FORCEPROP 1 LAST BODY_TYPE PLUMBING
J 0
(-3500 1850);
DISPLAY 0.872340 (-3500 1850);
PAINT GREEN (-3500 1850);
DISPLAY INVISIBLE (-3500 1850);
FORCEPROP 1 LAST HDL_TAP TRUE
J 0
(-3175 1675);
DISPLAY 0.872340 (-3175 1675);
DISPLAY INVISIBLE (-3175 1675);
FORCEPROP 1 LAST PATH I238
J 0
(-3502 1800);
DISPLAY 0.872340 (-3502 1800);
PAINT GREEN (-3502 1800);
DISPLAY INVISIBLE (-3502 1800);
FORCEADD TAP..1
(-3500 1750);
FORCEPROP 3 LASTPIN (-3550 1750) SIG_NAME M_C_CPU0_SB_CB<3>
J 0
(-3540 1760);
DISPLAY 0.659574 (-3540 1760);
PAINT MONO (-3540 1760);
DISPLAY INVISIBLE (-3540 1760);
FORCEPROP 1 LASTPIN (-3550 1750) BN 3
J 0
(-3562 1758);
DISPLAY 0.489362 (-3562 1758);
PAINT GREEN (-3562 1758);
FORCEPROP 2 LAST CDS_LIB mstr_standard
J 2
(-3500 1750);
DISPLAY 0.723404 (-3500 1750);
PAINT MONO (-3500 1750);
DISPLAY INVISIBLE (-3500 1750);
FORCEPROP 1 LAST BODY_TYPE PLUMBING
J 0
(-3500 1800);
DISPLAY 0.872340 (-3500 1800);
PAINT GREEN (-3500 1800);
DISPLAY INVISIBLE (-3500 1800);
FORCEPROP 1 LAST HDL_TAP TRUE
J 0
(-3175 1625);
DISPLAY 0.872340 (-3175 1625);
DISPLAY INVISIBLE (-3175 1625);
FORCEPROP 1 LAST PATH I239
J 0
(-3502 1750);
DISPLAY 0.872340 (-3502 1750);
PAINT GREEN (-3502 1750);
DISPLAY INVISIBLE (-3502 1750);
FORCEADD TAP..1
(-3500 1700);
FORCEPROP 3 LASTPIN (-3550 1700) SIG_NAME M_C_CPU0_SB_CB<4>
J 0
(-3540 1710);
DISPLAY 0.659574 (-3540 1710);
PAINT MONO (-3540 1710);
DISPLAY INVISIBLE (-3540 1710);
FORCEPROP 1 LASTPIN (-3550 1700) BN 4
J 0
(-3562 1708);
DISPLAY 0.489362 (-3562 1708);
PAINT GREEN (-3562 1708);
FORCEPROP 2 LAST CDS_LIB mstr_standard
J 2
(-3500 1700);
DISPLAY 0.723404 (-3500 1700);
PAINT MONO (-3500 1700);
DISPLAY INVISIBLE (-3500 1700);
FORCEPROP 1 LAST BODY_TYPE PLUMBING
J 0
(-3500 1750);
DISPLAY 0.872340 (-3500 1750);
PAINT GREEN (-3500 1750);
DISPLAY INVISIBLE (-3500 1750);
FORCEPROP 1 LAST HDL_TAP TRUE
J 0
(-3175 1575);
DISPLAY 0.872340 (-3175 1575);
DISPLAY INVISIBLE (-3175 1575);
FORCEPROP 1 LAST PATH I240
J 0
(-3502 1700);
DISPLAY 0.872340 (-3502 1700);
PAINT GREEN (-3502 1700);
DISPLAY INVISIBLE (-3502 1700);
FORCEADD TAP..1
(-3500 1650);
FORCEPROP 3 LASTPIN (-3550 1650) SIG_NAME M_C_CPU0_SB_CB<5>
J 0
(-3540 1660);
DISPLAY 0.659574 (-3540 1660);
PAINT MONO (-3540 1660);
DISPLAY INVISIBLE (-3540 1660);
FORCEPROP 1 LASTPIN (-3550 1650) BN 5
J 0
(-3562 1658);
DISPLAY 0.489362 (-3562 1658);
PAINT GREEN (-3562 1658);
FORCEPROP 2 LAST CDS_LIB mstr_standard
J 2
(-3500 1650);
DISPLAY 0.723404 (-3500 1650);
PAINT MONO (-3500 1650);
DISPLAY INVISIBLE (-3500 1650);
FORCEPROP 1 LAST BODY_TYPE PLUMBING
J 0
(-3500 1700);
DISPLAY 0.872340 (-3500 1700);
PAINT GREEN (-3500 1700);
DISPLAY INVISIBLE (-3500 1700);
FORCEPROP 1 LAST HDL_TAP TRUE
J 0
(-3175 1525);
DISPLAY 0.872340 (-3175 1525);
DISPLAY INVISIBLE (-3175 1525);
FORCEPROP 1 LAST PATH I241
J 0
(-3502 1650);
DISPLAY 0.872340 (-3502 1650);
PAINT GREEN (-3502 1650);
DISPLAY INVISIBLE (-3502 1650);
FORCEADD TAP..1
(-3500 1550);
FORCEPROP 3 LASTPIN (-3550 1550) SIG_NAME M_C_CPU0_SB_CB<7>
J 0
(-3540 1560);
DISPLAY 0.659574 (-3540 1560);
PAINT MONO (-3540 1560);
DISPLAY INVISIBLE (-3540 1560);
FORCEPROP 1 LASTPIN (-3550 1550) BN 7
J 0
(-3562 1558);
DISPLAY 0.489362 (-3562 1558);
PAINT GREEN (-3562 1558);
FORCEPROP 2 LAST CDS_LIB mstr_standard
J 2
(-3500 1550);
DISPLAY 0.723404 (-3500 1550);
PAINT MONO (-3500 1550);
DISPLAY INVISIBLE (-3500 1550);
FORCEPROP 1 LAST BODY_TYPE PLUMBING
J 0
(-3500 1600);
DISPLAY 0.872340 (-3500 1600);
PAINT GREEN (-3500 1600);
DISPLAY INVISIBLE (-3500 1600);
FORCEPROP 1 LAST HDL_TAP TRUE
J 0
(-3175 1425);
DISPLAY 0.872340 (-3175 1425);
DISPLAY INVISIBLE (-3175 1425);
FORCEPROP 1 LAST PATH I242
J 0
(-3502 1550);
DISPLAY 0.872340 (-3502 1550);
PAINT GREEN (-3502 1550);
DISPLAY INVISIBLE (-3502 1550);
FORCEADD TAP..1
(-3500 1600);
FORCEPROP 3 LASTPIN (-3550 1600) SIG_NAME M_C_CPU0_SB_CB<6>
J 0
(-3540 1610);
DISPLAY 0.659574 (-3540 1610);
PAINT MONO (-3540 1610);
DISPLAY INVISIBLE (-3540 1610);
FORCEPROP 1 LASTPIN (-3550 1600) BN 6
J 0
(-3562 1608);
DISPLAY 0.489362 (-3562 1608);
PAINT GREEN (-3562 1608);
FORCEPROP 2 LAST CDS_LIB mstr_standard
J 2
(-3500 1600);
DISPLAY 0.723404 (-3500 1600);
PAINT MONO (-3500 1600);
DISPLAY INVISIBLE (-3500 1600);
FORCEPROP 1 LAST BODY_TYPE PLUMBING
J 0
(-3500 1650);
DISPLAY 0.872340 (-3500 1650);
PAINT GREEN (-3500 1650);
DISPLAY INVISIBLE (-3500 1650);
FORCEPROP 1 LAST HDL_TAP TRUE
J 0
(-3175 1475);
DISPLAY 0.872340 (-3175 1475);
DISPLAY INVISIBLE (-3175 1475);
FORCEPROP 1 LAST PATH I243
J 0
(-3502 1600);
DISPLAY 0.872340 (-3502 1600);
PAINT GREEN (-3502 1600);
DISPLAY INVISIBLE (-3502 1600);
FORCEADD TAP..1
R 2
(-5925 5950);
FORCEPROP 3 LASTPIN (-5875 5950) SIG_NAME M_C_CPU0_SA_DQS_DP<0>
J 0
(-5865 5960);
DISPLAY 0.659574 (-5865 5960);
PAINT MONO (-5865 5960);
DISPLAY INVISIBLE (-5865 5960);
FORCEPROP 1 LASTPIN (-5875 5950) BN 0
J 2
(-5863 5958);
DISPLAY 0.489362 (-5863 5958);
PAINT GREEN (-5863 5958);
FORCEPROP 2 LAST CDS_LIB mstr_standard
J 2
(-5925 5950);
DISPLAY 0.723404 (-5925 5950);
PAINT MONO (-5925 5950);
DISPLAY INVISIBLE (-5925 5950);
FORCEPROP 1 LAST BODY_TYPE PLUMBING
J 2
(-5925 6000);
DISPLAY 0.872340 (-5925 6000);
PAINT GREEN (-5925 6000);
DISPLAY INVISIBLE (-5925 6000);
FORCEPROP 1 LAST HDL_TAP TRUE
J 2
(-6250 5825);
DISPLAY 0.872340 (-6250 5825);
DISPLAY INVISIBLE (-6250 5825);
FORCEPROP 1 LAST PATH I244
J 2
(-5923 5950);
DISPLAY 0.872340 (-5923 5950);
PAINT GREEN (-5923 5950);
DISPLAY INVISIBLE (-5923 5950);
FORCEADD TAP..1
R 2
(-5925 5850);
FORCEPROP 3 LASTPIN (-5875 5850) SIG_NAME M_C_CPU0_SA_DQS_DP<1>
J 0
(-5865 5860);
DISPLAY 0.659574 (-5865 5860);
PAINT MONO (-5865 5860);
DISPLAY INVISIBLE (-5865 5860);
FORCEPROP 1 LASTPIN (-5875 5850) BN 1
J 2
(-5863 5858);
DISPLAY 0.489362 (-5863 5858);
PAINT GREEN (-5863 5858);
FORCEPROP 2 LAST CDS_LIB mstr_standard
J 2
(-5925 5850);
DISPLAY 0.723404 (-5925 5850);
PAINT MONO (-5925 5850);
DISPLAY INVISIBLE (-5925 5850);
FORCEPROP 1 LAST BODY_TYPE PLUMBING
J 2
(-5925 5900);
DISPLAY 0.872340 (-5925 5900);
PAINT GREEN (-5925 5900);
DISPLAY INVISIBLE (-5925 5900);
FORCEPROP 1 LAST HDL_TAP TRUE
J 2
(-6250 5725);
DISPLAY 0.872340 (-6250 5725);
DISPLAY INVISIBLE (-6250 5725);
FORCEPROP 1 LAST PATH I245
J 2
(-5923 5850);
DISPLAY 0.872340 (-5923 5850);
PAINT GREEN (-5923 5850);
DISPLAY INVISIBLE (-5923 5850);
FORCEADD TAP..1
R 2
(-5925 5750);
FORCEPROP 3 LASTPIN (-5875 5750) SIG_NAME M_C_CPU0_SA_DQS_DP<2>
J 0
(-5865 5760);
DISPLAY 0.659574 (-5865 5760);
PAINT MONO (-5865 5760);
DISPLAY INVISIBLE (-5865 5760);
FORCEPROP 1 LASTPIN (-5875 5750) BN 2
J 2
(-5863 5758);
DISPLAY 0.489362 (-5863 5758);
PAINT GREEN (-5863 5758);
FORCEPROP 2 LAST CDS_LIB mstr_standard
J 2
(-5925 5750);
DISPLAY 0.723404 (-5925 5750);
PAINT MONO (-5925 5750);
DISPLAY INVISIBLE (-5925 5750);
FORCEPROP 1 LAST BODY_TYPE PLUMBING
J 2
(-5925 5800);
DISPLAY 0.872340 (-5925 5800);
PAINT GREEN (-5925 5800);
DISPLAY INVISIBLE (-5925 5800);
FORCEPROP 1 LAST HDL_TAP TRUE
J 2
(-6250 5625);
DISPLAY 0.872340 (-6250 5625);
DISPLAY INVISIBLE (-6250 5625);
FORCEPROP 1 LAST PATH I246
J 2
(-5923 5750);
DISPLAY 0.872340 (-5923 5750);
PAINT GREEN (-5923 5750);
DISPLAY INVISIBLE (-5923 5750);
FORCEADD TAP..1
R 2
(-5925 5650);
FORCEPROP 3 LASTPIN (-5875 5650) SIG_NAME M_C_CPU0_SA_DQS_DP<3>
J 0
(-5865 5660);
DISPLAY 0.659574 (-5865 5660);
PAINT MONO (-5865 5660);
DISPLAY INVISIBLE (-5865 5660);
FORCEPROP 1 LASTPIN (-5875 5650) BN 3
J 2
(-5863 5658);
DISPLAY 0.489362 (-5863 5658);
PAINT GREEN (-5863 5658);
FORCEPROP 2 LAST CDS_LIB mstr_standard
J 2
(-5925 5650);
DISPLAY 0.723404 (-5925 5650);
PAINT MONO (-5925 5650);
DISPLAY INVISIBLE (-5925 5650);
FORCEPROP 1 LAST BODY_TYPE PLUMBING
J 2
(-5925 5700);
DISPLAY 0.872340 (-5925 5700);
PAINT GREEN (-5925 5700);
DISPLAY INVISIBLE (-5925 5700);
FORCEPROP 1 LAST HDL_TAP TRUE
J 2
(-6250 5525);
DISPLAY 0.872340 (-6250 5525);
DISPLAY INVISIBLE (-6250 5525);
FORCEPROP 1 LAST PATH I247
J 2
(-5923 5650);
DISPLAY 0.872340 (-5923 5650);
PAINT GREEN (-5923 5650);
DISPLAY INVISIBLE (-5923 5650);
FORCEADD TAP..1
R 2
(-5925 5550);
FORCEPROP 3 LASTPIN (-5875 5550) SIG_NAME M_C_CPU0_SA_DQS_DP<4>
J 0
(-5865 5560);
DISPLAY 0.659574 (-5865 5560);
PAINT MONO (-5865 5560);
DISPLAY INVISIBLE (-5865 5560);
FORCEPROP 1 LASTPIN (-5875 5550) BN 4
J 2
(-5863 5558);
DISPLAY 0.489362 (-5863 5558);
PAINT GREEN (-5863 5558);
FORCEPROP 2 LAST CDS_LIB mstr_standard
J 2
(-5925 5550);
DISPLAY 0.723404 (-5925 5550);
PAINT MONO (-5925 5550);
DISPLAY INVISIBLE (-5925 5550);
FORCEPROP 1 LAST BODY_TYPE PLUMBING
J 2
(-5925 5600);
DISPLAY 0.872340 (-5925 5600);
PAINT GREEN (-5925 5600);
DISPLAY INVISIBLE (-5925 5600);
FORCEPROP 1 LAST HDL_TAP TRUE
J 2
(-6250 5425);
DISPLAY 0.872340 (-6250 5425);
DISPLAY INVISIBLE (-6250 5425);
FORCEPROP 1 LAST PATH I248
J 2
(-5923 5550);
DISPLAY 0.872340 (-5923 5550);
PAINT GREEN (-5923 5550);
DISPLAY INVISIBLE (-5923 5550);
FORCEADD TAP..1
R 2
(-5925 5450);
FORCEPROP 3 LASTPIN (-5875 5450) SIG_NAME M_C_CPU0_SA_DQS_DP<5>
J 0
(-5865 5460);
DISPLAY 0.659574 (-5865 5460);
PAINT MONO (-5865 5460);
DISPLAY INVISIBLE (-5865 5460);
FORCEPROP 1 LASTPIN (-5875 5450) BN 5
J 2
(-5863 5458);
DISPLAY 0.489362 (-5863 5458);
PAINT GREEN (-5863 5458);
FORCEPROP 2 LAST CDS_LIB mstr_standard
J 2
(-5925 5450);
DISPLAY 0.723404 (-5925 5450);
PAINT MONO (-5925 5450);
DISPLAY INVISIBLE (-5925 5450);
FORCEPROP 1 LAST BODY_TYPE PLUMBING
J 2
(-5925 5500);
DISPLAY 0.872340 (-5925 5500);
PAINT GREEN (-5925 5500);
DISPLAY INVISIBLE (-5925 5500);
FORCEPROP 1 LAST HDL_TAP TRUE
J 2
(-6250 5325);
DISPLAY 0.872340 (-6250 5325);
DISPLAY INVISIBLE (-6250 5325);
FORCEPROP 1 LAST PATH I249
J 2
(-5923 5450);
DISPLAY 0.872340 (-5923 5450);
PAINT GREEN (-5923 5450);
DISPLAY INVISIBLE (-5923 5450);
FORCEADD TAP..1
R 2
(-5925 5350);
FORCEPROP 3 LASTPIN (-5875 5350) SIG_NAME M_C_CPU0_SA_DQS_DP<6>
J 0
(-5865 5360);
DISPLAY 0.659574 (-5865 5360);
PAINT MONO (-5865 5360);
DISPLAY INVISIBLE (-5865 5360);
FORCEPROP 1 LASTPIN (-5875 5350) BN 6
J 2
(-5863 5358);
DISPLAY 0.489362 (-5863 5358);
PAINT GREEN (-5863 5358);
FORCEPROP 2 LAST CDS_LIB mstr_standard
J 2
(-5925 5350);
DISPLAY 0.723404 (-5925 5350);
PAINT MONO (-5925 5350);
DISPLAY INVISIBLE (-5925 5350);
FORCEPROP 1 LAST BODY_TYPE PLUMBING
J 2
(-5925 5400);
DISPLAY 0.872340 (-5925 5400);
PAINT GREEN (-5925 5400);
DISPLAY INVISIBLE (-5925 5400);
FORCEPROP 1 LAST HDL_TAP TRUE
J 2
(-6250 5225);
DISPLAY 0.872340 (-6250 5225);
DISPLAY INVISIBLE (-6250 5225);
FORCEPROP 1 LAST PATH I250
J 2
(-5923 5350);
DISPLAY 0.872340 (-5923 5350);
PAINT GREEN (-5923 5350);
DISPLAY INVISIBLE (-5923 5350);
FORCEADD TAP..1
R 2
(-5925 5250);
FORCEPROP 3 LASTPIN (-5875 5250) SIG_NAME M_C_CPU0_SA_DQS_DP<7>
J 0
(-5865 5260);
DISPLAY 0.659574 (-5865 5260);
PAINT MONO (-5865 5260);
DISPLAY INVISIBLE (-5865 5260);
FORCEPROP 1 LASTPIN (-5875 5250) BN 7
J 2
(-5863 5258);
DISPLAY 0.489362 (-5863 5258);
PAINT GREEN (-5863 5258);
FORCEPROP 2 LAST CDS_LIB mstr_standard
J 2
(-5925 5250);
DISPLAY 0.723404 (-5925 5250);
PAINT MONO (-5925 5250);
DISPLAY INVISIBLE (-5925 5250);
FORCEPROP 1 LAST BODY_TYPE PLUMBING
J 2
(-5925 5300);
DISPLAY 0.872340 (-5925 5300);
PAINT GREEN (-5925 5300);
DISPLAY INVISIBLE (-5925 5300);
FORCEPROP 1 LAST HDL_TAP TRUE
J 2
(-6250 5125);
DISPLAY 0.872340 (-6250 5125);
DISPLAY INVISIBLE (-6250 5125);
FORCEPROP 1 LAST PATH I251
J 2
(-5923 5250);
DISPLAY 0.872340 (-5923 5250);
PAINT GREEN (-5923 5250);
DISPLAY INVISIBLE (-5923 5250);
FORCEADD TAP..1
R 2
(-5925 5150);
FORCEPROP 3 LASTPIN (-5875 5150) SIG_NAME M_C_CPU0_SA_DQS_DP<8>
J 0
(-5865 5160);
DISPLAY 0.659574 (-5865 5160);
PAINT MONO (-5865 5160);
DISPLAY INVISIBLE (-5865 5160);
FORCEPROP 1 LASTPIN (-5875 5150) BN 8
J 2
(-5863 5158);
DISPLAY 0.489362 (-5863 5158);
PAINT GREEN (-5863 5158);
FORCEPROP 2 LAST CDS_LIB mstr_standard
J 2
(-5925 5150);
DISPLAY 0.723404 (-5925 5150);
PAINT MONO (-5925 5150);
DISPLAY INVISIBLE (-5925 5150);
FORCEPROP 1 LAST BODY_TYPE PLUMBING
J 2
(-5925 5200);
DISPLAY 0.872340 (-5925 5200);
PAINT GREEN (-5925 5200);
DISPLAY INVISIBLE (-5925 5200);
FORCEPROP 1 LAST HDL_TAP TRUE
J 2
(-6250 5025);
DISPLAY 0.872340 (-6250 5025);
DISPLAY INVISIBLE (-6250 5025);
FORCEPROP 1 LAST PATH I252
J 2
(-5923 5150);
DISPLAY 0.872340 (-5923 5150);
PAINT GREEN (-5923 5150);
DISPLAY INVISIBLE (-5923 5150);
FORCEADD TAP..1
R 2
(-5925 5050);
FORCEPROP 3 LASTPIN (-5875 5050) SIG_NAME M_C_CPU0_SA_DQS_DP<9>
J 0
(-5865 5060);
DISPLAY 0.659574 (-5865 5060);
PAINT MONO (-5865 5060);
DISPLAY INVISIBLE (-5865 5060);
FORCEPROP 1 LASTPIN (-5875 5050) BN 9
J 2
(-5863 5058);
DISPLAY 0.489362 (-5863 5058);
PAINT GREEN (-5863 5058);
FORCEPROP 2 LAST CDS_LIB mstr_standard
J 2
(-5925 5050);
DISPLAY 0.723404 (-5925 5050);
PAINT MONO (-5925 5050);
DISPLAY INVISIBLE (-5925 5050);
FORCEPROP 1 LAST BODY_TYPE PLUMBING
J 2
(-5925 5100);
DISPLAY 0.872340 (-5925 5100);
PAINT GREEN (-5925 5100);
DISPLAY INVISIBLE (-5925 5100);
FORCEPROP 1 LAST HDL_TAP TRUE
J 2
(-6250 4925);
DISPLAY 0.872340 (-6250 4925);
DISPLAY INVISIBLE (-6250 4925);
FORCEPROP 1 LAST PATH I253
J 2
(-5923 5050);
DISPLAY 0.872340 (-5923 5050);
PAINT GREEN (-5923 5050);
DISPLAY INVISIBLE (-5923 5050);
FORCEADD TAP..1
R 2
(-5925 4900);
FORCEPROP 3 LASTPIN (-5875 4900) SIG_NAME M_C_CPU0_SB_DQS_DP<0>
J 0
(-5865 4910);
DISPLAY 0.659574 (-5865 4910);
PAINT MONO (-5865 4910);
DISPLAY INVISIBLE (-5865 4910);
FORCEPROP 1 LASTPIN (-5875 4900) BN 0
J 2
(-5863 4908);
DISPLAY 0.489362 (-5863 4908);
PAINT GREEN (-5863 4908);
FORCEPROP 2 LAST CDS_LIB mstr_standard
J 2
(-5925 4900);
DISPLAY 0.723404 (-5925 4900);
PAINT MONO (-5925 4900);
DISPLAY INVISIBLE (-5925 4900);
FORCEPROP 1 LAST BODY_TYPE PLUMBING
J 2
(-5925 4950);
DISPLAY 0.872340 (-5925 4950);
PAINT GREEN (-5925 4950);
DISPLAY INVISIBLE (-5925 4950);
FORCEPROP 1 LAST HDL_TAP TRUE
J 2
(-6250 4775);
DISPLAY 0.872340 (-6250 4775);
DISPLAY INVISIBLE (-6250 4775);
FORCEPROP 1 LAST PATH I254
J 2
(-5923 4900);
DISPLAY 0.872340 (-5923 4900);
PAINT GREEN (-5923 4900);
DISPLAY INVISIBLE (-5923 4900);
FORCEADD TAP..1
R 2
(-5925 4800);
FORCEPROP 3 LASTPIN (-5875 4800) SIG_NAME M_C_CPU0_SB_DQS_DP<1>
J 0
(-5865 4810);
DISPLAY 0.659574 (-5865 4810);
PAINT MONO (-5865 4810);
DISPLAY INVISIBLE (-5865 4810);
FORCEPROP 1 LASTPIN (-5875 4800) BN 1
J 2
(-5863 4808);
DISPLAY 0.489362 (-5863 4808);
PAINT GREEN (-5863 4808);
FORCEPROP 2 LAST CDS_LIB mstr_standard
J 2
(-5925 4800);
DISPLAY 0.723404 (-5925 4800);
PAINT MONO (-5925 4800);
DISPLAY INVISIBLE (-5925 4800);
FORCEPROP 1 LAST BODY_TYPE PLUMBING
J 2
(-5925 4850);
DISPLAY 0.872340 (-5925 4850);
PAINT GREEN (-5925 4850);
DISPLAY INVISIBLE (-5925 4850);
FORCEPROP 1 LAST HDL_TAP TRUE
J 2
(-6250 4675);
DISPLAY 0.872340 (-6250 4675);
DISPLAY INVISIBLE (-6250 4675);
FORCEPROP 1 LAST PATH I255
J 2
(-5923 4800);
DISPLAY 0.872340 (-5923 4800);
PAINT GREEN (-5923 4800);
DISPLAY INVISIBLE (-5923 4800);
FORCEADD TAP..1
R 2
(-5925 4700);
FORCEPROP 3 LASTPIN (-5875 4700) SIG_NAME M_C_CPU0_SB_DQS_DP<2>
J 0
(-5865 4710);
DISPLAY 0.659574 (-5865 4710);
PAINT MONO (-5865 4710);
DISPLAY INVISIBLE (-5865 4710);
FORCEPROP 1 LASTPIN (-5875 4700) BN 2
J 2
(-5863 4708);
DISPLAY 0.489362 (-5863 4708);
PAINT GREEN (-5863 4708);
FORCEPROP 2 LAST CDS_LIB mstr_standard
J 2
(-5925 4700);
DISPLAY 0.723404 (-5925 4700);
PAINT MONO (-5925 4700);
DISPLAY INVISIBLE (-5925 4700);
FORCEPROP 1 LAST BODY_TYPE PLUMBING
J 2
(-5925 4750);
DISPLAY 0.872340 (-5925 4750);
PAINT GREEN (-5925 4750);
DISPLAY INVISIBLE (-5925 4750);
FORCEPROP 1 LAST HDL_TAP TRUE
J 2
(-6250 4575);
DISPLAY 0.872340 (-6250 4575);
DISPLAY INVISIBLE (-6250 4575);
FORCEPROP 1 LAST PATH I256
J 2
(-5923 4700);
DISPLAY 0.872340 (-5923 4700);
PAINT GREEN (-5923 4700);
DISPLAY INVISIBLE (-5923 4700);
FORCEADD TAP..1
R 2
(-5925 4500);
FORCEPROP 3 LASTPIN (-5875 4500) SIG_NAME M_C_CPU0_SB_DQS_DP<4>
J 0
(-5865 4510);
DISPLAY 0.659574 (-5865 4510);
PAINT MONO (-5865 4510);
DISPLAY INVISIBLE (-5865 4510);
FORCEPROP 1 LASTPIN (-5875 4500) BN 4
J 2
(-5863 4508);
DISPLAY 0.489362 (-5863 4508);
PAINT GREEN (-5863 4508);
FORCEPROP 2 LAST CDS_LIB mstr_standard
J 2
(-5925 4500);
DISPLAY 0.723404 (-5925 4500);
PAINT MONO (-5925 4500);
DISPLAY INVISIBLE (-5925 4500);
FORCEPROP 1 LAST BODY_TYPE PLUMBING
J 2
(-5925 4550);
DISPLAY 0.872340 (-5925 4550);
PAINT GREEN (-5925 4550);
DISPLAY INVISIBLE (-5925 4550);
FORCEPROP 1 LAST HDL_TAP TRUE
J 2
(-6250 4375);
DISPLAY 0.872340 (-6250 4375);
DISPLAY INVISIBLE (-6250 4375);
FORCEPROP 1 LAST PATH I257
J 2
(-5923 4500);
DISPLAY 0.872340 (-5923 4500);
PAINT GREEN (-5923 4500);
DISPLAY INVISIBLE (-5923 4500);
FORCEADD TAP..1
R 2
(-5925 4600);
FORCEPROP 3 LASTPIN (-5875 4600) SIG_NAME M_C_CPU0_SB_DQS_DP<3>
J 0
(-5865 4610);
DISPLAY 0.659574 (-5865 4610);
PAINT MONO (-5865 4610);
DISPLAY INVISIBLE (-5865 4610);
FORCEPROP 1 LASTPIN (-5875 4600) BN 3
J 2
(-5863 4608);
DISPLAY 0.489362 (-5863 4608);
PAINT GREEN (-5863 4608);
FORCEPROP 2 LAST CDS_LIB mstr_standard
J 2
(-5925 4600);
DISPLAY 0.723404 (-5925 4600);
PAINT MONO (-5925 4600);
DISPLAY INVISIBLE (-5925 4600);
FORCEPROP 1 LAST BODY_TYPE PLUMBING
J 2
(-5925 4650);
DISPLAY 0.872340 (-5925 4650);
PAINT GREEN (-5925 4650);
DISPLAY INVISIBLE (-5925 4650);
FORCEPROP 1 LAST HDL_TAP TRUE
J 2
(-6250 4475);
DISPLAY 0.872340 (-6250 4475);
DISPLAY INVISIBLE (-6250 4475);
FORCEPROP 1 LAST PATH I258
J 2
(-5923 4600);
DISPLAY 0.872340 (-5923 4600);
PAINT GREEN (-5923 4600);
DISPLAY INVISIBLE (-5923 4600);
FORCEADD TAP..1
R 2
(-5925 4400);
FORCEPROP 3 LASTPIN (-5875 4400) SIG_NAME M_C_CPU0_SB_DQS_DP<5>
J 0
(-5865 4410);
DISPLAY 0.659574 (-5865 4410);
PAINT MONO (-5865 4410);
DISPLAY INVISIBLE (-5865 4410);
FORCEPROP 1 LASTPIN (-5875 4400) BN 5
J 2
(-5863 4408);
DISPLAY 0.489362 (-5863 4408);
PAINT GREEN (-5863 4408);
FORCEPROP 2 LAST CDS_LIB mstr_standard
J 2
(-5925 4400);
DISPLAY 0.723404 (-5925 4400);
PAINT MONO (-5925 4400);
DISPLAY INVISIBLE (-5925 4400);
FORCEPROP 1 LAST BODY_TYPE PLUMBING
J 2
(-5925 4450);
DISPLAY 0.872340 (-5925 4450);
PAINT GREEN (-5925 4450);
DISPLAY INVISIBLE (-5925 4450);
FORCEPROP 1 LAST HDL_TAP TRUE
J 2
(-6250 4275);
DISPLAY 0.872340 (-6250 4275);
DISPLAY INVISIBLE (-6250 4275);
FORCEPROP 1 LAST PATH I259
J 2
(-5923 4400);
DISPLAY 0.872340 (-5923 4400);
PAINT GREEN (-5923 4400);
DISPLAY INVISIBLE (-5923 4400);
FORCEADD TAP..1
R 2
(-5925 4300);
FORCEPROP 3 LASTPIN (-5875 4300) SIG_NAME M_C_CPU0_SB_DQS_DP<6>
J 0
(-5865 4310);
DISPLAY 0.659574 (-5865 4310);
PAINT MONO (-5865 4310);
DISPLAY INVISIBLE (-5865 4310);
FORCEPROP 1 LASTPIN (-5875 4300) BN 6
J 2
(-5863 4308);
DISPLAY 0.489362 (-5863 4308);
PAINT GREEN (-5863 4308);
FORCEPROP 2 LAST CDS_LIB mstr_standard
J 2
(-5925 4300);
DISPLAY 0.723404 (-5925 4300);
PAINT MONO (-5925 4300);
DISPLAY INVISIBLE (-5925 4300);
FORCEPROP 1 LAST BODY_TYPE PLUMBING
J 2
(-5925 4350);
DISPLAY 0.872340 (-5925 4350);
PAINT GREEN (-5925 4350);
DISPLAY INVISIBLE (-5925 4350);
FORCEPROP 1 LAST HDL_TAP TRUE
J 2
(-6250 4175);
DISPLAY 0.872340 (-6250 4175);
DISPLAY INVISIBLE (-6250 4175);
FORCEPROP 1 LAST PATH I260
J 2
(-5923 4300);
DISPLAY 0.872340 (-5923 4300);
PAINT GREEN (-5923 4300);
DISPLAY INVISIBLE (-5923 4300);
FORCEADD TAP..1
R 2
(-5925 4100);
FORCEPROP 3 LASTPIN (-5875 4100) SIG_NAME M_C_CPU0_SB_DQS_DP<8>
J 0
(-5865 4110);
DISPLAY 0.659574 (-5865 4110);
PAINT MONO (-5865 4110);
DISPLAY INVISIBLE (-5865 4110);
FORCEPROP 1 LASTPIN (-5875 4100) BN 8
J 2
(-5863 4108);
DISPLAY 0.489362 (-5863 4108);
PAINT GREEN (-5863 4108);
FORCEPROP 2 LAST CDS_LIB mstr_standard
J 2
(-5925 4100);
DISPLAY 0.723404 (-5925 4100);
PAINT MONO (-5925 4100);
DISPLAY INVISIBLE (-5925 4100);
FORCEPROP 1 LAST BODY_TYPE PLUMBING
J 2
(-5925 4150);
DISPLAY 0.872340 (-5925 4150);
PAINT GREEN (-5925 4150);
DISPLAY INVISIBLE (-5925 4150);
FORCEPROP 1 LAST HDL_TAP TRUE
J 2
(-6250 3975);
DISPLAY 0.872340 (-6250 3975);
DISPLAY INVISIBLE (-6250 3975);
FORCEPROP 1 LAST PATH I261
J 2
(-5923 4100);
DISPLAY 0.872340 (-5923 4100);
PAINT GREEN (-5923 4100);
DISPLAY INVISIBLE (-5923 4100);
FORCEADD TAP..1
R 2
(-5925 4200);
FORCEPROP 3 LASTPIN (-5875 4200) SIG_NAME M_C_CPU0_SB_DQS_DP<7>
J 0
(-5865 4210);
DISPLAY 0.659574 (-5865 4210);
PAINT MONO (-5865 4210);
DISPLAY INVISIBLE (-5865 4210);
FORCEPROP 1 LASTPIN (-5875 4200) BN 7
J 2
(-5863 4208);
DISPLAY 0.489362 (-5863 4208);
PAINT GREEN (-5863 4208);
FORCEPROP 2 LAST CDS_LIB mstr_standard
J 2
(-5925 4200);
DISPLAY 0.723404 (-5925 4200);
PAINT MONO (-5925 4200);
DISPLAY INVISIBLE (-5925 4200);
FORCEPROP 1 LAST BODY_TYPE PLUMBING
J 2
(-5925 4250);
DISPLAY 0.872340 (-5925 4250);
PAINT GREEN (-5925 4250);
DISPLAY INVISIBLE (-5925 4250);
FORCEPROP 1 LAST HDL_TAP TRUE
J 2
(-6250 4075);
DISPLAY 0.872340 (-6250 4075);
DISPLAY INVISIBLE (-6250 4075);
FORCEPROP 1 LAST PATH I262
J 2
(-5923 4200);
DISPLAY 0.872340 (-5923 4200);
PAINT GREEN (-5923 4200);
DISPLAY INVISIBLE (-5923 4200);
FORCEADD TAP..1
R 2
(-6125 5800);
FORCEPROP 3 LASTPIN (-6075 5800) SIG_NAME M_C_CPU0_SA_DQS_DN<1>
J 0
(-6065 5810);
DISPLAY 0.659574 (-6065 5810);
PAINT MONO (-6065 5810);
DISPLAY INVISIBLE (-6065 5810);
FORCEPROP 1 LASTPIN (-6075 5800) BN 1
J 2
(-6063 5808);
DISPLAY 0.489362 (-6063 5808);
PAINT GREEN (-6063 5808);
FORCEPROP 2 LAST CDS_LIB mstr_standard
J 2
(-6125 5800);
DISPLAY 0.723404 (-6125 5800);
PAINT MONO (-6125 5800);
DISPLAY INVISIBLE (-6125 5800);
FORCEPROP 1 LAST BODY_TYPE PLUMBING
J 2
(-6125 5850);
DISPLAY 0.872340 (-6125 5850);
PAINT GREEN (-6125 5850);
DISPLAY INVISIBLE (-6125 5850);
FORCEPROP 1 LAST HDL_TAP TRUE
J 2
(-6450 5675);
DISPLAY 0.872340 (-6450 5675);
DISPLAY INVISIBLE (-6450 5675);
FORCEPROP 1 LAST PATH I263
J 2
(-6123 5800);
DISPLAY 0.872340 (-6123 5800);
PAINT GREEN (-6123 5800);
DISPLAY INVISIBLE (-6123 5800);
FORCEADD TAP..1
R 2
(-6125 5700);
FORCEPROP 3 LASTPIN (-6075 5700) SIG_NAME M_C_CPU0_SA_DQS_DN<2>
J 0
(-6065 5710);
DISPLAY 0.659574 (-6065 5710);
PAINT MONO (-6065 5710);
DISPLAY INVISIBLE (-6065 5710);
FORCEPROP 1 LASTPIN (-6075 5700) BN 2
J 2
(-6063 5708);
DISPLAY 0.489362 (-6063 5708);
PAINT GREEN (-6063 5708);
FORCEPROP 2 LAST CDS_LIB mstr_standard
J 2
(-6125 5700);
DISPLAY 0.723404 (-6125 5700);
PAINT MONO (-6125 5700);
DISPLAY INVISIBLE (-6125 5700);
FORCEPROP 1 LAST BODY_TYPE PLUMBING
J 2
(-6125 5750);
DISPLAY 0.872340 (-6125 5750);
PAINT GREEN (-6125 5750);
DISPLAY INVISIBLE (-6125 5750);
FORCEPROP 1 LAST HDL_TAP TRUE
J 2
(-6450 5575);
DISPLAY 0.872340 (-6450 5575);
DISPLAY INVISIBLE (-6450 5575);
FORCEPROP 1 LAST PATH I264
J 2
(-6123 5700);
DISPLAY 0.872340 (-6123 5700);
PAINT GREEN (-6123 5700);
DISPLAY INVISIBLE (-6123 5700);
FORCEADD TAP..1
R 2
(-6125 5900);
FORCEPROP 3 LASTPIN (-6075 5900) SIG_NAME M_C_CPU0_SA_DQS_DN<0>
J 0
(-6065 5910);
DISPLAY 0.659574 (-6065 5910);
PAINT MONO (-6065 5910);
DISPLAY INVISIBLE (-6065 5910);
FORCEPROP 1 LASTPIN (-6075 5900) BN 0
J 2
(-6063 5908);
DISPLAY 0.489362 (-6063 5908);
PAINT GREEN (-6063 5908);
FORCEPROP 2 LAST CDS_LIB mstr_standard
J 2
(-6125 5900);
DISPLAY 0.723404 (-6125 5900);
PAINT MONO (-6125 5900);
DISPLAY INVISIBLE (-6125 5900);
FORCEPROP 1 LAST BODY_TYPE PLUMBING
J 2
(-6125 5950);
DISPLAY 0.872340 (-6125 5950);
PAINT GREEN (-6125 5950);
DISPLAY INVISIBLE (-6125 5950);
FORCEPROP 1 LAST HDL_TAP TRUE
J 2
(-6450 5775);
DISPLAY 0.872340 (-6450 5775);
DISPLAY INVISIBLE (-6450 5775);
FORCEPROP 1 LAST PATH I265
J 2
(-6123 5900);
DISPLAY 0.872340 (-6123 5900);
PAINT GREEN (-6123 5900);
DISPLAY INVISIBLE (-6123 5900);
FORCEADD TAP..1
R 2
(-6125 5400);
FORCEPROP 3 LASTPIN (-6075 5400) SIG_NAME M_C_CPU0_SA_DQS_DN<5>
J 0
(-6065 5410);
DISPLAY 0.659574 (-6065 5410);
PAINT MONO (-6065 5410);
DISPLAY INVISIBLE (-6065 5410);
FORCEPROP 1 LASTPIN (-6075 5400) BN 5
J 2
(-6063 5408);
DISPLAY 0.489362 (-6063 5408);
PAINT GREEN (-6063 5408);
FORCEPROP 2 LAST CDS_LIB mstr_standard
J 2
(-6125 5400);
DISPLAY 0.723404 (-6125 5400);
PAINT MONO (-6125 5400);
DISPLAY INVISIBLE (-6125 5400);
FORCEPROP 1 LAST BODY_TYPE PLUMBING
J 2
(-6125 5450);
DISPLAY 0.872340 (-6125 5450);
PAINT GREEN (-6125 5450);
DISPLAY INVISIBLE (-6125 5450);
FORCEPROP 1 LAST HDL_TAP TRUE
J 2
(-6450 5275);
DISPLAY 0.872340 (-6450 5275);
DISPLAY INVISIBLE (-6450 5275);
FORCEPROP 1 LAST PATH I266
J 2
(-6123 5400);
DISPLAY 0.872340 (-6123 5400);
PAINT GREEN (-6123 5400);
DISPLAY INVISIBLE (-6123 5400);
FORCEADD TAP..1
R 2
(-6125 5600);
FORCEPROP 3 LASTPIN (-6075 5600) SIG_NAME M_C_CPU0_SA_DQS_DN<3>
J 0
(-6065 5610);
DISPLAY 0.659574 (-6065 5610);
PAINT MONO (-6065 5610);
DISPLAY INVISIBLE (-6065 5610);
FORCEPROP 1 LASTPIN (-6075 5600) BN 3
J 2
(-6063 5608);
DISPLAY 0.489362 (-6063 5608);
PAINT GREEN (-6063 5608);
FORCEPROP 2 LAST CDS_LIB mstr_standard
J 2
(-6125 5600);
DISPLAY 0.723404 (-6125 5600);
PAINT MONO (-6125 5600);
DISPLAY INVISIBLE (-6125 5600);
FORCEPROP 1 LAST BODY_TYPE PLUMBING
J 2
(-6125 5650);
DISPLAY 0.872340 (-6125 5650);
PAINT GREEN (-6125 5650);
DISPLAY INVISIBLE (-6125 5650);
FORCEPROP 1 LAST HDL_TAP TRUE
J 2
(-6450 5475);
DISPLAY 0.872340 (-6450 5475);
DISPLAY INVISIBLE (-6450 5475);
FORCEPROP 1 LAST PATH I267
J 2
(-6123 5600);
DISPLAY 0.872340 (-6123 5600);
PAINT GREEN (-6123 5600);
DISPLAY INVISIBLE (-6123 5600);
FORCEADD TAP..1
R 2
(-6125 5500);
FORCEPROP 3 LASTPIN (-6075 5500) SIG_NAME M_C_CPU0_SA_DQS_DN<4>
J 0
(-6065 5510);
DISPLAY 0.659574 (-6065 5510);
PAINT MONO (-6065 5510);
DISPLAY INVISIBLE (-6065 5510);
FORCEPROP 1 LASTPIN (-6075 5500) BN 4
J 2
(-6063 5508);
DISPLAY 0.489362 (-6063 5508);
PAINT GREEN (-6063 5508);
FORCEPROP 2 LAST CDS_LIB mstr_standard
J 2
(-6125 5500);
DISPLAY 0.723404 (-6125 5500);
PAINT MONO (-6125 5500);
DISPLAY INVISIBLE (-6125 5500);
FORCEPROP 1 LAST BODY_TYPE PLUMBING
J 2
(-6125 5550);
DISPLAY 0.872340 (-6125 5550);
PAINT GREEN (-6125 5550);
DISPLAY INVISIBLE (-6125 5550);
FORCEPROP 1 LAST HDL_TAP TRUE
J 2
(-6450 5375);
DISPLAY 0.872340 (-6450 5375);
DISPLAY INVISIBLE (-6450 5375);
FORCEPROP 1 LAST PATH I268
J 2
(-6123 5500);
DISPLAY 0.872340 (-6123 5500);
PAINT GREEN (-6123 5500);
DISPLAY INVISIBLE (-6123 5500);
FORCEADD TAP..1
R 2
(-6125 5100);
FORCEPROP 3 LASTPIN (-6075 5100) SIG_NAME M_C_CPU0_SA_DQS_DN<8>
J 0
(-6065 5110);
DISPLAY 0.659574 (-6065 5110);
PAINT MONO (-6065 5110);
DISPLAY INVISIBLE (-6065 5110);
FORCEPROP 1 LASTPIN (-6075 5100) BN 8
J 2
(-6063 5108);
DISPLAY 0.489362 (-6063 5108);
PAINT GREEN (-6063 5108);
FORCEPROP 2 LAST CDS_LIB mstr_standard
J 2
(-6125 5100);
DISPLAY 0.723404 (-6125 5100);
PAINT MONO (-6125 5100);
DISPLAY INVISIBLE (-6125 5100);
FORCEPROP 1 LAST BODY_TYPE PLUMBING
J 2
(-6125 5150);
DISPLAY 0.872340 (-6125 5150);
PAINT GREEN (-6125 5150);
DISPLAY INVISIBLE (-6125 5150);
FORCEPROP 1 LAST HDL_TAP TRUE
J 2
(-6450 4975);
DISPLAY 0.872340 (-6450 4975);
DISPLAY INVISIBLE (-6450 4975);
FORCEPROP 1 LAST PATH I269
J 2
(-6123 5100);
DISPLAY 0.872340 (-6123 5100);
PAINT GREEN (-6123 5100);
DISPLAY INVISIBLE (-6123 5100);
FORCEADD TAP..1
R 2
(-6125 5200);
FORCEPROP 3 LASTPIN (-6075 5200) SIG_NAME M_C_CPU0_SA_DQS_DN<7>
J 0
(-6065 5210);
DISPLAY 0.659574 (-6065 5210);
PAINT MONO (-6065 5210);
DISPLAY INVISIBLE (-6065 5210);
FORCEPROP 1 LASTPIN (-6075 5200) BN 7
J 2
(-6063 5208);
DISPLAY 0.489362 (-6063 5208);
PAINT GREEN (-6063 5208);
FORCEPROP 2 LAST CDS_LIB mstr_standard
J 2
(-6125 5200);
DISPLAY 0.723404 (-6125 5200);
PAINT MONO (-6125 5200);
DISPLAY INVISIBLE (-6125 5200);
FORCEPROP 1 LAST BODY_TYPE PLUMBING
J 2
(-6125 5250);
DISPLAY 0.872340 (-6125 5250);
PAINT GREEN (-6125 5250);
DISPLAY INVISIBLE (-6125 5250);
FORCEPROP 1 LAST HDL_TAP TRUE
J 2
(-6450 5075);
DISPLAY 0.872340 (-6450 5075);
DISPLAY INVISIBLE (-6450 5075);
FORCEPROP 1 LAST PATH I270
J 2
(-6123 5200);
DISPLAY 0.872340 (-6123 5200);
PAINT GREEN (-6123 5200);
DISPLAY INVISIBLE (-6123 5200);
FORCEADD TAP..1
R 2
(-6125 5300);
FORCEPROP 3 LASTPIN (-6075 5300) SIG_NAME M_C_CPU0_SA_DQS_DN<6>
J 0
(-6065 5310);
DISPLAY 0.659574 (-6065 5310);
PAINT MONO (-6065 5310);
DISPLAY INVISIBLE (-6065 5310);
FORCEPROP 1 LASTPIN (-6075 5300) BN 6
J 2
(-6063 5308);
DISPLAY 0.489362 (-6063 5308);
PAINT GREEN (-6063 5308);
FORCEPROP 2 LAST CDS_LIB mstr_standard
J 2
(-6125 5300);
DISPLAY 0.723404 (-6125 5300);
PAINT MONO (-6125 5300);
DISPLAY INVISIBLE (-6125 5300);
FORCEPROP 1 LAST BODY_TYPE PLUMBING
J 2
(-6125 5350);
DISPLAY 0.872340 (-6125 5350);
PAINT GREEN (-6125 5350);
DISPLAY INVISIBLE (-6125 5350);
FORCEPROP 1 LAST HDL_TAP TRUE
J 2
(-6450 5175);
DISPLAY 0.872340 (-6450 5175);
DISPLAY INVISIBLE (-6450 5175);
FORCEPROP 1 LAST PATH I271
J 2
(-6123 5300);
DISPLAY 0.872340 (-6123 5300);
PAINT GREEN (-6123 5300);
DISPLAY INVISIBLE (-6123 5300);
FORCEADD OFFPAGE..3
R 2
(-6825 5975);
FORCEPROP 2 LAST $XR0 87 
J 0
(-7074 5975);
DISPLAY 0.638298 (-7074 5975);
PAINT MONO (-7074 5975);
FORCEPROP 2 LAST PATH I272
J 0
(-7125 6025);
DISPLAY 1.021277 (-7125 6025);
DISPLAY INVISIBLE (-7125 6025);
FORCEPROP 1 LAST COMMENT_BODY TRUE
J 2
(-6775 5875);
DISPLAY 0.872340 (-6775 5875);
PAINT GREEN (-6775 5875);
DISPLAY INVISIBLE (-6775 5875);
FORCEPROP 1 LAST OFFPAGE TRUE
J 2
(-7150 5850);
DISPLAY 0.872340 (-7150 5850);
PAINT GREEN (-7150 5850);
DISPLAY INVISIBLE (-7150 5850);
FORCEPROP 2 LAST CDS_LIB standard
J 0
(-6825 5975);
DISPLAY INVISIBLE (-6825 5975);
FORCEADD OFFPAGE..3
R 2
(-6825 5925);
FORCEPROP 2 LAST $XR0 87 
J 0
(-7074 5925);
DISPLAY 0.638298 (-7074 5925);
PAINT MONO (-7074 5925);
FORCEPROP 2 LAST PATH I273
J 0
(-7125 5975);
DISPLAY 1.021277 (-7125 5975);
DISPLAY INVISIBLE (-7125 5975);
FORCEPROP 1 LAST COMMENT_BODY TRUE
J 2
(-6775 5825);
DISPLAY 0.872340 (-6775 5825);
PAINT GREEN (-6775 5825);
DISPLAY INVISIBLE (-6775 5825);
FORCEPROP 1 LAST OFFPAGE TRUE
J 2
(-7150 5800);
DISPLAY 0.872340 (-7150 5800);
PAINT GREEN (-7150 5800);
DISPLAY INVISIBLE (-7150 5800);
FORCEPROP 2 LAST CDS_LIB standard
J 0
(-6825 5925);
DISPLAY INVISIBLE (-6825 5925);
FORCEADD TAP..1
R 2
(-6125 4850);
FORCEPROP 3 LASTPIN (-6075 4850) SIG_NAME M_C_CPU0_SB_DQS_DN<0>
J 0
(-6065 4860);
DISPLAY 0.659574 (-6065 4860);
PAINT MONO (-6065 4860);
DISPLAY INVISIBLE (-6065 4860);
FORCEPROP 1 LASTPIN (-6075 4850) BN 0
J 2
(-6063 4858);
DISPLAY 0.489362 (-6063 4858);
PAINT GREEN (-6063 4858);
FORCEPROP 2 LAST CDS_LIB mstr_standard
J 2
(-6125 4850);
DISPLAY 0.723404 (-6125 4850);
PAINT MONO (-6125 4850);
DISPLAY INVISIBLE (-6125 4850);
FORCEPROP 1 LAST BODY_TYPE PLUMBING
J 2
(-6125 4900);
DISPLAY 0.872340 (-6125 4900);
PAINT GREEN (-6125 4900);
DISPLAY INVISIBLE (-6125 4900);
FORCEPROP 1 LAST HDL_TAP TRUE
J 2
(-6450 4725);
DISPLAY 0.872340 (-6450 4725);
DISPLAY INVISIBLE (-6450 4725);
FORCEPROP 1 LAST PATH I274
J 2
(-6123 4850);
DISPLAY 0.872340 (-6123 4850);
PAINT GREEN (-6123 4850);
DISPLAY INVISIBLE (-6123 4850);
FORCEADD TAP..1
R 2
(-6125 5000);
FORCEPROP 3 LASTPIN (-6075 5000) SIG_NAME M_C_CPU0_SA_DQS_DN<9>
J 0
(-6065 5010);
DISPLAY 0.659574 (-6065 5010);
PAINT MONO (-6065 5010);
DISPLAY INVISIBLE (-6065 5010);
FORCEPROP 1 LASTPIN (-6075 5000) BN 9
J 2
(-6063 5008);
DISPLAY 0.489362 (-6063 5008);
PAINT GREEN (-6063 5008);
FORCEPROP 2 LAST CDS_LIB mstr_standard
J 2
(-6125 5000);
DISPLAY 0.723404 (-6125 5000);
PAINT MONO (-6125 5000);
DISPLAY INVISIBLE (-6125 5000);
FORCEPROP 1 LAST BODY_TYPE PLUMBING
J 2
(-6125 5050);
DISPLAY 0.872340 (-6125 5050);
PAINT GREEN (-6125 5050);
DISPLAY INVISIBLE (-6125 5050);
FORCEPROP 1 LAST HDL_TAP TRUE
J 2
(-6450 4875);
DISPLAY 0.872340 (-6450 4875);
DISPLAY INVISIBLE (-6450 4875);
FORCEPROP 1 LAST PATH I275
J 2
(-6123 5000);
DISPLAY 0.872340 (-6123 5000);
PAINT GREEN (-6123 5000);
DISPLAY INVISIBLE (-6123 5000);
FORCEADD TAP..1
R 2
(-6125 4650);
FORCEPROP 3 LASTPIN (-6075 4650) SIG_NAME M_C_CPU0_SB_DQS_DN<2>
J 0
(-6065 4660);
DISPLAY 0.659574 (-6065 4660);
PAINT MONO (-6065 4660);
DISPLAY INVISIBLE (-6065 4660);
FORCEPROP 1 LASTPIN (-6075 4650) BN 2
J 2
(-6063 4658);
DISPLAY 0.489362 (-6063 4658);
PAINT GREEN (-6063 4658);
FORCEPROP 2 LAST CDS_LIB mstr_standard
J 2
(-6125 4650);
DISPLAY 0.723404 (-6125 4650);
PAINT MONO (-6125 4650);
DISPLAY INVISIBLE (-6125 4650);
FORCEPROP 1 LAST BODY_TYPE PLUMBING
J 2
(-6125 4700);
DISPLAY 0.872340 (-6125 4700);
PAINT GREEN (-6125 4700);
DISPLAY INVISIBLE (-6125 4700);
FORCEPROP 1 LAST HDL_TAP TRUE
J 2
(-6450 4525);
DISPLAY 0.872340 (-6450 4525);
DISPLAY INVISIBLE (-6450 4525);
FORCEPROP 1 LAST PATH I276
J 2
(-6123 4650);
DISPLAY 0.872340 (-6123 4650);
PAINT GREEN (-6123 4650);
DISPLAY INVISIBLE (-6123 4650);
FORCEADD TAP..1
R 2
(-6125 4750);
FORCEPROP 3 LASTPIN (-6075 4750) SIG_NAME M_C_CPU0_SB_DQS_DN<1>
J 0
(-6065 4760);
DISPLAY 0.659574 (-6065 4760);
PAINT MONO (-6065 4760);
DISPLAY INVISIBLE (-6065 4760);
FORCEPROP 1 LASTPIN (-6075 4750) BN 1
J 2
(-6063 4758);
DISPLAY 0.489362 (-6063 4758);
PAINT GREEN (-6063 4758);
FORCEPROP 2 LAST CDS_LIB mstr_standard
J 2
(-6125 4750);
DISPLAY 0.723404 (-6125 4750);
PAINT MONO (-6125 4750);
DISPLAY INVISIBLE (-6125 4750);
FORCEPROP 1 LAST BODY_TYPE PLUMBING
J 2
(-6125 4800);
DISPLAY 0.872340 (-6125 4800);
PAINT GREEN (-6125 4800);
DISPLAY INVISIBLE (-6125 4800);
FORCEPROP 1 LAST HDL_TAP TRUE
J 2
(-6450 4625);
DISPLAY 0.872340 (-6450 4625);
DISPLAY INVISIBLE (-6450 4625);
FORCEPROP 1 LAST PATH I277
J 2
(-6123 4750);
DISPLAY 0.872340 (-6123 4750);
PAINT GREEN (-6123 4750);
DISPLAY INVISIBLE (-6123 4750);
FORCEADD TAP..1
R 2
(-6125 4350);
FORCEPROP 3 LASTPIN (-6075 4350) SIG_NAME M_C_CPU0_SB_DQS_DN<5>
J 0
(-6065 4360);
DISPLAY 0.659574 (-6065 4360);
PAINT MONO (-6065 4360);
DISPLAY INVISIBLE (-6065 4360);
FORCEPROP 1 LASTPIN (-6075 4350) BN 5
J 2
(-6063 4358);
DISPLAY 0.489362 (-6063 4358);
PAINT GREEN (-6063 4358);
FORCEPROP 2 LAST CDS_LIB mstr_standard
J 2
(-6125 4350);
DISPLAY 0.723404 (-6125 4350);
PAINT MONO (-6125 4350);
DISPLAY INVISIBLE (-6125 4350);
FORCEPROP 1 LAST BODY_TYPE PLUMBING
J 2
(-6125 4400);
DISPLAY 0.872340 (-6125 4400);
PAINT GREEN (-6125 4400);
DISPLAY INVISIBLE (-6125 4400);
FORCEPROP 1 LAST HDL_TAP TRUE
J 2
(-6450 4225);
DISPLAY 0.872340 (-6450 4225);
DISPLAY INVISIBLE (-6450 4225);
FORCEPROP 1 LAST PATH I278
J 2
(-6123 4350);
DISPLAY 0.872340 (-6123 4350);
PAINT GREEN (-6123 4350);
DISPLAY INVISIBLE (-6123 4350);
FORCEADD TAP..1
R 2
(-6125 4550);
FORCEPROP 3 LASTPIN (-6075 4550) SIG_NAME M_C_CPU0_SB_DQS_DN<3>
J 0
(-6065 4560);
DISPLAY 0.659574 (-6065 4560);
PAINT MONO (-6065 4560);
DISPLAY INVISIBLE (-6065 4560);
FORCEPROP 1 LASTPIN (-6075 4550) BN 3
J 2
(-6063 4558);
DISPLAY 0.489362 (-6063 4558);
PAINT GREEN (-6063 4558);
FORCEPROP 2 LAST CDS_LIB mstr_standard
J 2
(-6125 4550);
DISPLAY 0.723404 (-6125 4550);
PAINT MONO (-6125 4550);
DISPLAY INVISIBLE (-6125 4550);
FORCEPROP 1 LAST BODY_TYPE PLUMBING
J 2
(-6125 4600);
DISPLAY 0.872340 (-6125 4600);
PAINT GREEN (-6125 4600);
DISPLAY INVISIBLE (-6125 4600);
FORCEPROP 1 LAST HDL_TAP TRUE
J 2
(-6450 4425);
DISPLAY 0.872340 (-6450 4425);
DISPLAY INVISIBLE (-6450 4425);
FORCEPROP 1 LAST PATH I279
J 2
(-6123 4550);
DISPLAY 0.872340 (-6123 4550);
PAINT GREEN (-6123 4550);
DISPLAY INVISIBLE (-6123 4550);
FORCEADD TAP..1
R 2
(-6125 4450);
FORCEPROP 3 LASTPIN (-6075 4450) SIG_NAME M_C_CPU0_SB_DQS_DN<4>
J 0
(-6065 4460);
DISPLAY 0.659574 (-6065 4460);
PAINT MONO (-6065 4460);
DISPLAY INVISIBLE (-6065 4460);
FORCEPROP 1 LASTPIN (-6075 4450) BN 4
J 2
(-6063 4458);
DISPLAY 0.489362 (-6063 4458);
PAINT GREEN (-6063 4458);
FORCEPROP 2 LAST CDS_LIB mstr_standard
J 2
(-6125 4450);
DISPLAY 0.723404 (-6125 4450);
PAINT MONO (-6125 4450);
DISPLAY INVISIBLE (-6125 4450);
FORCEPROP 1 LAST BODY_TYPE PLUMBING
J 2
(-6125 4500);
DISPLAY 0.872340 (-6125 4500);
PAINT GREEN (-6125 4500);
DISPLAY INVISIBLE (-6125 4500);
FORCEPROP 1 LAST HDL_TAP TRUE
J 2
(-6450 4325);
DISPLAY 0.872340 (-6450 4325);
DISPLAY INVISIBLE (-6450 4325);
FORCEPROP 1 LAST PATH I280
J 2
(-6123 4450);
DISPLAY 0.872340 (-6123 4450);
PAINT GREEN (-6123 4450);
DISPLAY INVISIBLE (-6123 4450);
FORCEADD TAP..1
R 2
(-6125 4150);
FORCEPROP 3 LASTPIN (-6075 4150) SIG_NAME M_C_CPU0_SB_DQS_DN<7>
J 0
(-6065 4160);
DISPLAY 0.659574 (-6065 4160);
PAINT MONO (-6065 4160);
DISPLAY INVISIBLE (-6065 4160);
FORCEPROP 1 LASTPIN (-6075 4150) BN 7
J 2
(-6063 4158);
DISPLAY 0.489362 (-6063 4158);
PAINT GREEN (-6063 4158);
FORCEPROP 2 LAST CDS_LIB mstr_standard
J 2
(-6125 4150);
DISPLAY 0.723404 (-6125 4150);
PAINT MONO (-6125 4150);
DISPLAY INVISIBLE (-6125 4150);
FORCEPROP 1 LAST BODY_TYPE PLUMBING
J 2
(-6125 4200);
DISPLAY 0.872340 (-6125 4200);
PAINT GREEN (-6125 4200);
DISPLAY INVISIBLE (-6125 4200);
FORCEPROP 1 LAST HDL_TAP TRUE
J 2
(-6450 4025);
DISPLAY 0.872340 (-6450 4025);
DISPLAY INVISIBLE (-6450 4025);
FORCEPROP 1 LAST PATH I281
J 2
(-6123 4150);
DISPLAY 0.872340 (-6123 4150);
PAINT GREEN (-6123 4150);
DISPLAY INVISIBLE (-6123 4150);
FORCEADD TAP..1
R 2
(-6125 4250);
FORCEPROP 3 LASTPIN (-6075 4250) SIG_NAME M_C_CPU0_SB_DQS_DN<6>
J 0
(-6065 4260);
DISPLAY 0.659574 (-6065 4260);
PAINT MONO (-6065 4260);
DISPLAY INVISIBLE (-6065 4260);
FORCEPROP 1 LASTPIN (-6075 4250) BN 6
J 2
(-6063 4258);
DISPLAY 0.489362 (-6063 4258);
PAINT GREEN (-6063 4258);
FORCEPROP 2 LAST CDS_LIB mstr_standard
J 2
(-6125 4250);
DISPLAY 0.723404 (-6125 4250);
PAINT MONO (-6125 4250);
DISPLAY INVISIBLE (-6125 4250);
FORCEPROP 1 LAST BODY_TYPE PLUMBING
J 2
(-6125 4300);
DISPLAY 0.872340 (-6125 4300);
PAINT GREEN (-6125 4300);
DISPLAY INVISIBLE (-6125 4300);
FORCEPROP 1 LAST HDL_TAP TRUE
J 2
(-6450 4125);
DISPLAY 0.872340 (-6450 4125);
DISPLAY INVISIBLE (-6450 4125);
FORCEPROP 1 LAST PATH I282
J 2
(-6123 4250);
DISPLAY 0.872340 (-6123 4250);
PAINT GREEN (-6123 4250);
DISPLAY INVISIBLE (-6123 4250);
FORCEADD OFFPAGE..3
R 2
(-6825 4925);
FORCEPROP 2 LAST $XR0 87 
J 0
(-7074 4925);
DISPLAY 0.638298 (-7074 4925);
PAINT MONO (-7074 4925);
FORCEPROP 2 LAST PATH I283
J 0
(-7125 4975);
DISPLAY 1.021277 (-7125 4975);
DISPLAY INVISIBLE (-7125 4975);
FORCEPROP 1 LAST COMMENT_BODY TRUE
J 2
(-6775 4825);
DISPLAY 0.872340 (-6775 4825);
PAINT GREEN (-6775 4825);
DISPLAY INVISIBLE (-6775 4825);
FORCEPROP 1 LAST OFFPAGE TRUE
J 2
(-7150 4800);
DISPLAY 0.872340 (-7150 4800);
PAINT GREEN (-7150 4800);
DISPLAY INVISIBLE (-7150 4800);
FORCEPROP 2 LAST CDS_LIB standard
J 0
(-6825 4925);
DISPLAY INVISIBLE (-6825 4925);
FORCEADD OFFPAGE..3
R 2
(-6825 4875);
FORCEPROP 2 LAST $XR0 87 
J 0
(-7074 4875);
DISPLAY 0.638298 (-7074 4875);
PAINT MONO (-7074 4875);
FORCEPROP 2 LAST PATH I284
J 0
(-7125 4925);
DISPLAY 1.021277 (-7125 4925);
DISPLAY INVISIBLE (-7125 4925);
FORCEPROP 1 LAST COMMENT_BODY TRUE
J 2
(-6775 4775);
DISPLAY 0.872340 (-6775 4775);
PAINT GREEN (-6775 4775);
DISPLAY INVISIBLE (-6775 4775);
FORCEPROP 1 LAST OFFPAGE TRUE
J 2
(-7150 4750);
DISPLAY 0.872340 (-7150 4750);
PAINT GREEN (-7150 4750);
DISPLAY INVISIBLE (-7150 4750);
FORCEPROP 2 LAST CDS_LIB standard
J 0
(-6825 4875);
DISPLAY INVISIBLE (-6825 4875);
FORCEADD TAP..1
R 2
(-5925 4000);
FORCEPROP 3 LASTPIN (-5875 4000) SIG_NAME M_C_CPU0_SB_DQS_DP<9>
J 0
(-5865 4010);
DISPLAY 0.659574 (-5865 4010);
PAINT MONO (-5865 4010);
DISPLAY INVISIBLE (-5865 4010);
FORCEPROP 1 LASTPIN (-5875 4000) BN 9
J 2
(-5863 4008);
DISPLAY 0.489362 (-5863 4008);
PAINT GREEN (-5863 4008);
FORCEPROP 2 LAST CDS_LIB mstr_standard
J 2
(-5925 4000);
DISPLAY 0.723404 (-5925 4000);
PAINT MONO (-5925 4000);
DISPLAY INVISIBLE (-5925 4000);
FORCEPROP 1 LAST BODY_TYPE PLUMBING
J 2
(-5925 4050);
DISPLAY 0.872340 (-5925 4050);
PAINT GREEN (-5925 4050);
DISPLAY INVISIBLE (-5925 4050);
FORCEPROP 1 LAST HDL_TAP TRUE
J 2
(-6250 3875);
DISPLAY 0.872340 (-6250 3875);
DISPLAY INVISIBLE (-6250 3875);
FORCEPROP 1 LAST PATH I285
J 2
(-5923 4000);
DISPLAY 0.872340 (-5923 4000);
PAINT GREEN (-5923 4000);
DISPLAY INVISIBLE (-5923 4000);
FORCEADD TAP..1
R 2
(-6125 3950);
FORCEPROP 3 LASTPIN (-6075 3950) SIG_NAME M_C_CPU0_SB_DQS_DN<9>
J 0
(-6065 3960);
DISPLAY 0.659574 (-6065 3960);
PAINT MONO (-6065 3960);
DISPLAY INVISIBLE (-6065 3960);
FORCEPROP 1 LASTPIN (-6075 3950) BN 9
J 2
(-6063 3958);
DISPLAY 0.489362 (-6063 3958);
PAINT GREEN (-6063 3958);
FORCEPROP 2 LAST CDS_LIB mstr_standard
J 2
(-6125 3950);
DISPLAY 0.723404 (-6125 3950);
PAINT MONO (-6125 3950);
DISPLAY INVISIBLE (-6125 3950);
FORCEPROP 1 LAST BODY_TYPE PLUMBING
J 2
(-6125 4000);
DISPLAY 0.872340 (-6125 4000);
PAINT GREEN (-6125 4000);
DISPLAY INVISIBLE (-6125 4000);
FORCEPROP 1 LAST HDL_TAP TRUE
J 2
(-6450 3825);
DISPLAY 0.872340 (-6450 3825);
DISPLAY INVISIBLE (-6450 3825);
FORCEPROP 1 LAST PATH I286
J 2
(-6123 3950);
DISPLAY 0.872340 (-6123 3950);
PAINT GREEN (-6123 3950);
DISPLAY INVISIBLE (-6123 3950);
FORCEADD TAP..1
R 2
(-6125 4050);
FORCEPROP 3 LASTPIN (-6075 4050) SIG_NAME M_C_CPU0_SB_DQS_DN<8>
J 0
(-6065 4060);
DISPLAY 0.659574 (-6065 4060);
PAINT MONO (-6065 4060);
DISPLAY INVISIBLE (-6065 4060);
FORCEPROP 1 LASTPIN (-6075 4050) BN 8
J 2
(-6063 4058);
DISPLAY 0.489362 (-6063 4058);
PAINT GREEN (-6063 4058);
FORCEPROP 2 LAST CDS_LIB mstr_standard
J 2
(-6125 4050);
DISPLAY 0.723404 (-6125 4050);
PAINT MONO (-6125 4050);
DISPLAY INVISIBLE (-6125 4050);
FORCEPROP 1 LAST BODY_TYPE PLUMBING
J 2
(-6125 4100);
DISPLAY 0.872340 (-6125 4100);
PAINT GREEN (-6125 4100);
DISPLAY INVISIBLE (-6125 4100);
FORCEPROP 1 LAST HDL_TAP TRUE
J 2
(-6450 3925);
DISPLAY 0.872340 (-6450 3925);
DISPLAY INVISIBLE (-6450 3925);
FORCEPROP 1 LAST PATH I287
J 2
(-6123 4050);
DISPLAY 0.872340 (-6123 4050);
PAINT GREEN (-6123 4050);
DISPLAY INVISIBLE (-6123 4050);
FORCEADD TAP..1
R 2
(-6125 3750);
FORCEPROP 3 LASTPIN (-6075 3750) SIG_NAME M_C_CPU0_SA_CA<1>
J 0
(-6065 3760);
DISPLAY 0.659574 (-6065 3760);
PAINT MONO (-6065 3760);
DISPLAY INVISIBLE (-6065 3760);
FORCEPROP 1 LASTPIN (-6075 3750) BN 1
J 2
(-6063 3758);
DISPLAY 0.489362 (-6063 3758);
PAINT GREEN (-6063 3758);
FORCEPROP 2 LAST CDS_LIB mstr_standard
J 0
(-6125 3750);
DISPLAY 0.723404 (-6125 3750);
PAINT MONO (-6125 3750);
DISPLAY INVISIBLE (-6125 3750);
FORCEPROP 1 LAST BODY_TYPE PLUMBING
J 2
(-6125 3800);
DISPLAY 0.872340 (-6125 3800);
PAINT GREEN (-6125 3800);
DISPLAY INVISIBLE (-6125 3800);
FORCEPROP 1 LAST HDL_TAP TRUE
J 2
(-6450 3625);
DISPLAY 0.872340 (-6450 3625);
DISPLAY INVISIBLE (-6450 3625);
FORCEPROP 1 LAST PATH I288
J 2
(-6123 3750);
DISPLAY 0.872340 (-6123 3750);
PAINT GREEN (-6123 3750);
DISPLAY INVISIBLE (-6123 3750);
FORCEADD TAP..1
R 2
(-6125 3800);
FORCEPROP 3 LASTPIN (-6075 3800) SIG_NAME M_C_CPU0_SA_CA<0>
J 0
(-6065 3810);
DISPLAY 0.659574 (-6065 3810);
PAINT MONO (-6065 3810);
DISPLAY INVISIBLE (-6065 3810);
FORCEPROP 1 LASTPIN (-6075 3800) BN 0
J 2
(-6063 3808);
DISPLAY 0.489362 (-6063 3808);
PAINT GREEN (-6063 3808);
FORCEPROP 2 LAST CDS_LIB mstr_standard
J 0
(-6125 3800);
DISPLAY 0.723404 (-6125 3800);
PAINT MONO (-6125 3800);
DISPLAY INVISIBLE (-6125 3800);
FORCEPROP 1 LAST BODY_TYPE PLUMBING
J 2
(-6125 3850);
DISPLAY 0.872340 (-6125 3850);
PAINT GREEN (-6125 3850);
DISPLAY INVISIBLE (-6125 3850);
FORCEPROP 1 LAST HDL_TAP TRUE
J 2
(-6450 3675);
DISPLAY 0.872340 (-6450 3675);
DISPLAY INVISIBLE (-6450 3675);
FORCEPROP 1 LAST PATH I289
J 2
(-6123 3800);
DISPLAY 0.872340 (-6123 3800);
PAINT GREEN (-6123 3800);
DISPLAY INVISIBLE (-6123 3800);
FORCEADD TAP..1
R 2
(-6125 3700);
FORCEPROP 3 LASTPIN (-6075 3700) SIG_NAME M_C_CPU0_SA_CA<2>
J 0
(-6065 3710);
DISPLAY 0.659574 (-6065 3710);
PAINT MONO (-6065 3710);
DISPLAY INVISIBLE (-6065 3710);
FORCEPROP 1 LASTPIN (-6075 3700) BN 2
J 2
(-6063 3708);
DISPLAY 0.489362 (-6063 3708);
PAINT GREEN (-6063 3708);
FORCEPROP 2 LAST CDS_LIB mstr_standard
J 0
(-6125 3700);
DISPLAY 0.723404 (-6125 3700);
PAINT MONO (-6125 3700);
DISPLAY INVISIBLE (-6125 3700);
FORCEPROP 1 LAST BODY_TYPE PLUMBING
J 2
(-6125 3750);
DISPLAY 0.872340 (-6125 3750);
PAINT GREEN (-6125 3750);
DISPLAY INVISIBLE (-6125 3750);
FORCEPROP 1 LAST HDL_TAP TRUE
J 2
(-6450 3575);
DISPLAY 0.872340 (-6450 3575);
DISPLAY INVISIBLE (-6450 3575);
FORCEPROP 1 LAST PATH I290
J 2
(-6123 3700);
DISPLAY 0.872340 (-6123 3700);
PAINT GREEN (-6123 3700);
DISPLAY INVISIBLE (-6123 3700);
FORCEADD TAP..1
R 2
(-6125 3650);
FORCEPROP 3 LASTPIN (-6075 3650) SIG_NAME M_C_CPU0_SA_CA<3>
J 0
(-6065 3660);
DISPLAY 0.659574 (-6065 3660);
PAINT MONO (-6065 3660);
DISPLAY INVISIBLE (-6065 3660);
FORCEPROP 1 LASTPIN (-6075 3650) BN 3
J 2
(-6063 3658);
DISPLAY 0.489362 (-6063 3658);
PAINT GREEN (-6063 3658);
FORCEPROP 2 LAST CDS_LIB mstr_standard
J 0
(-6125 3650);
DISPLAY 0.723404 (-6125 3650);
PAINT MONO (-6125 3650);
DISPLAY INVISIBLE (-6125 3650);
FORCEPROP 1 LAST BODY_TYPE PLUMBING
J 2
(-6125 3700);
DISPLAY 0.872340 (-6125 3700);
PAINT GREEN (-6125 3700);
DISPLAY INVISIBLE (-6125 3700);
FORCEPROP 1 LAST HDL_TAP TRUE
J 2
(-6450 3525);
DISPLAY 0.872340 (-6450 3525);
DISPLAY INVISIBLE (-6450 3525);
FORCEPROP 1 LAST PATH I291
J 2
(-6123 3650);
DISPLAY 0.872340 (-6123 3650);
PAINT GREEN (-6123 3650);
DISPLAY INVISIBLE (-6123 3650);
FORCEADD TAP..1
R 2
(-6125 3600);
FORCEPROP 3 LASTPIN (-6075 3600) SIG_NAME M_C_CPU0_SA_CA<4>
J 0
(-6065 3610);
DISPLAY 0.659574 (-6065 3610);
PAINT MONO (-6065 3610);
DISPLAY INVISIBLE (-6065 3610);
FORCEPROP 1 LASTPIN (-6075 3600) BN 4
J 2
(-6063 3608);
DISPLAY 0.489362 (-6063 3608);
PAINT GREEN (-6063 3608);
FORCEPROP 2 LAST CDS_LIB mstr_standard
J 0
(-6125 3600);
DISPLAY 0.723404 (-6125 3600);
PAINT MONO (-6125 3600);
DISPLAY INVISIBLE (-6125 3600);
FORCEPROP 1 LAST BODY_TYPE PLUMBING
J 2
(-6125 3650);
DISPLAY 0.872340 (-6125 3650);
PAINT GREEN (-6125 3650);
DISPLAY INVISIBLE (-6125 3650);
FORCEPROP 1 LAST HDL_TAP TRUE
J 2
(-6450 3475);
DISPLAY 0.872340 (-6450 3475);
DISPLAY INVISIBLE (-6450 3475);
FORCEPROP 1 LAST PATH I292
J 2
(-6123 3600);
DISPLAY 0.872340 (-6123 3600);
PAINT GREEN (-6123 3600);
DISPLAY INVISIBLE (-6123 3600);
FORCEADD TAP..1
R 2
(-6125 3550);
FORCEPROP 3 LASTPIN (-6075 3550) SIG_NAME M_C_CPU0_SA_CA<5>
J 0
(-6065 3560);
DISPLAY 0.659574 (-6065 3560);
PAINT MONO (-6065 3560);
DISPLAY INVISIBLE (-6065 3560);
FORCEPROP 1 LASTPIN (-6075 3550) BN 5
J 2
(-6063 3558);
DISPLAY 0.489362 (-6063 3558);
PAINT GREEN (-6063 3558);
FORCEPROP 2 LAST CDS_LIB mstr_standard
J 0
(-6125 3550);
DISPLAY 0.723404 (-6125 3550);
PAINT MONO (-6125 3550);
DISPLAY INVISIBLE (-6125 3550);
FORCEPROP 1 LAST BODY_TYPE PLUMBING
J 2
(-6125 3600);
DISPLAY 0.872340 (-6125 3600);
PAINT GREEN (-6125 3600);
DISPLAY INVISIBLE (-6125 3600);
FORCEPROP 1 LAST HDL_TAP TRUE
J 2
(-6450 3425);
DISPLAY 0.872340 (-6450 3425);
DISPLAY INVISIBLE (-6450 3425);
FORCEPROP 1 LAST PATH I293
J 2
(-6123 3550);
DISPLAY 0.872340 (-6123 3550);
PAINT GREEN (-6123 3550);
DISPLAY INVISIBLE (-6123 3550);
FORCEADD TAP..1
R 2
(-6125 3500);
FORCEPROP 3 LASTPIN (-6075 3500) SIG_NAME M_C_CPU0_SA_CA<6>
J 0
(-6065 3510);
DISPLAY 0.659574 (-6065 3510);
PAINT MONO (-6065 3510);
DISPLAY INVISIBLE (-6065 3510);
FORCEPROP 1 LASTPIN (-6075 3500) BN 6
J 2
(-6063 3508);
DISPLAY 0.489362 (-6063 3508);
PAINT GREEN (-6063 3508);
FORCEPROP 2 LAST CDS_LIB mstr_standard
J 0
(-6125 3500);
DISPLAY 0.723404 (-6125 3500);
PAINT MONO (-6125 3500);
DISPLAY INVISIBLE (-6125 3500);
FORCEPROP 1 LAST BODY_TYPE PLUMBING
J 2
(-6125 3550);
DISPLAY 0.872340 (-6125 3550);
PAINT GREEN (-6125 3550);
DISPLAY INVISIBLE (-6125 3550);
FORCEPROP 1 LAST HDL_TAP TRUE
J 2
(-6450 3375);
DISPLAY 0.872340 (-6450 3375);
DISPLAY INVISIBLE (-6450 3375);
FORCEPROP 1 LAST PATH I294
J 2
(-6123 3500);
DISPLAY 0.872340 (-6123 3500);
PAINT GREEN (-6123 3500);
DISPLAY INVISIBLE (-6123 3500);
FORCEADD TAP..1
R 2
(-6125 3400);
FORCEPROP 3 LASTPIN (-6075 3400) SIG_NAME M_C_CPU0_SB_CA<0>
J 0
(-6065 3410);
DISPLAY 0.659574 (-6065 3410);
PAINT MONO (-6065 3410);
DISPLAY INVISIBLE (-6065 3410);
FORCEPROP 1 LASTPIN (-6075 3400) BN 0
J 2
(-6063 3408);
DISPLAY 0.489362 (-6063 3408);
PAINT GREEN (-6063 3408);
FORCEPROP 2 LAST CDS_LIB mstr_standard
J 0
(-6125 3400);
DISPLAY 0.723404 (-6125 3400);
PAINT MONO (-6125 3400);
DISPLAY INVISIBLE (-6125 3400);
FORCEPROP 1 LAST BODY_TYPE PLUMBING
J 2
(-6125 3450);
DISPLAY 0.872340 (-6125 3450);
PAINT GREEN (-6125 3450);
DISPLAY INVISIBLE (-6125 3450);
FORCEPROP 1 LAST HDL_TAP TRUE
J 2
(-6450 3275);
DISPLAY 0.872340 (-6450 3275);
DISPLAY INVISIBLE (-6450 3275);
FORCEPROP 1 LAST PATH I295
J 2
(-6123 3400);
DISPLAY 0.872340 (-6123 3400);
PAINT GREEN (-6123 3400);
DISPLAY INVISIBLE (-6123 3400);
FORCEADD TAP..1
R 2
(-6125 3350);
FORCEPROP 3 LASTPIN (-6075 3350) SIG_NAME M_C_CPU0_SB_CA<1>
J 0
(-6065 3360);
DISPLAY 0.659574 (-6065 3360);
PAINT MONO (-6065 3360);
DISPLAY INVISIBLE (-6065 3360);
FORCEPROP 1 LASTPIN (-6075 3350) BN 1
J 2
(-6063 3358);
DISPLAY 0.489362 (-6063 3358);
PAINT GREEN (-6063 3358);
FORCEPROP 2 LAST CDS_LIB mstr_standard
J 0
(-6125 3350);
DISPLAY 0.723404 (-6125 3350);
PAINT MONO (-6125 3350);
DISPLAY INVISIBLE (-6125 3350);
FORCEPROP 1 LAST BODY_TYPE PLUMBING
J 2
(-6125 3400);
DISPLAY 0.872340 (-6125 3400);
PAINT GREEN (-6125 3400);
DISPLAY INVISIBLE (-6125 3400);
FORCEPROP 1 LAST HDL_TAP TRUE
J 2
(-6450 3225);
DISPLAY 0.872340 (-6450 3225);
DISPLAY INVISIBLE (-6450 3225);
FORCEPROP 1 LAST PATH I296
J 2
(-6123 3350);
DISPLAY 0.872340 (-6123 3350);
PAINT GREEN (-6123 3350);
DISPLAY INVISIBLE (-6123 3350);
FORCEADD TAP..1
R 2
(-6125 3250);
FORCEPROP 3 LASTPIN (-6075 3250) SIG_NAME M_C_CPU0_SB_CA<3>
J 0
(-6065 3260);
DISPLAY 0.659574 (-6065 3260);
PAINT MONO (-6065 3260);
DISPLAY INVISIBLE (-6065 3260);
FORCEPROP 1 LASTPIN (-6075 3250) BN 3
J 2
(-6063 3258);
DISPLAY 0.489362 (-6063 3258);
PAINT GREEN (-6063 3258);
FORCEPROP 2 LAST CDS_LIB mstr_standard
J 0
(-6125 3250);
DISPLAY 0.723404 (-6125 3250);
PAINT MONO (-6125 3250);
DISPLAY INVISIBLE (-6125 3250);
FORCEPROP 1 LAST BODY_TYPE PLUMBING
J 2
(-6125 3300);
DISPLAY 0.872340 (-6125 3300);
PAINT GREEN (-6125 3300);
DISPLAY INVISIBLE (-6125 3300);
FORCEPROP 1 LAST HDL_TAP TRUE
J 2
(-6450 3125);
DISPLAY 0.872340 (-6450 3125);
DISPLAY INVISIBLE (-6450 3125);
FORCEPROP 1 LAST PATH I297
J 2
(-6123 3250);
DISPLAY 0.872340 (-6123 3250);
PAINT GREEN (-6123 3250);
DISPLAY INVISIBLE (-6123 3250);
FORCEADD TAP..1
R 2
(-6125 3300);
FORCEPROP 3 LASTPIN (-6075 3300) SIG_NAME M_C_CPU0_SB_CA<2>
J 0
(-6065 3310);
DISPLAY 0.659574 (-6065 3310);
PAINT MONO (-6065 3310);
DISPLAY INVISIBLE (-6065 3310);
FORCEPROP 1 LASTPIN (-6075 3300) BN 2
J 2
(-6063 3308);
DISPLAY 0.489362 (-6063 3308);
PAINT GREEN (-6063 3308);
FORCEPROP 2 LAST CDS_LIB mstr_standard
J 0
(-6125 3300);
DISPLAY 0.723404 (-6125 3300);
PAINT MONO (-6125 3300);
DISPLAY INVISIBLE (-6125 3300);
FORCEPROP 1 LAST BODY_TYPE PLUMBING
J 2
(-6125 3350);
DISPLAY 0.872340 (-6125 3350);
PAINT GREEN (-6125 3350);
DISPLAY INVISIBLE (-6125 3350);
FORCEPROP 1 LAST HDL_TAP TRUE
J 2
(-6450 3175);
DISPLAY 0.872340 (-6450 3175);
DISPLAY INVISIBLE (-6450 3175);
FORCEPROP 1 LAST PATH I298
J 2
(-6123 3300);
DISPLAY 0.872340 (-6123 3300);
PAINT GREEN (-6123 3300);
DISPLAY INVISIBLE (-6123 3300);
FORCEADD TAP..1
R 2
(-6125 3200);
FORCEPROP 3 LASTPIN (-6075 3200) SIG_NAME M_C_CPU0_SB_CA<4>
J 0
(-6065 3210);
DISPLAY 0.659574 (-6065 3210);
PAINT MONO (-6065 3210);
DISPLAY INVISIBLE (-6065 3210);
FORCEPROP 1 LASTPIN (-6075 3200) BN 4
J 2
(-6063 3208);
DISPLAY 0.489362 (-6063 3208);
PAINT GREEN (-6063 3208);
FORCEPROP 2 LAST CDS_LIB mstr_standard
J 0
(-6125 3200);
DISPLAY 0.723404 (-6125 3200);
PAINT MONO (-6125 3200);
DISPLAY INVISIBLE (-6125 3200);
FORCEPROP 1 LAST BODY_TYPE PLUMBING
J 2
(-6125 3250);
DISPLAY 0.872340 (-6125 3250);
PAINT GREEN (-6125 3250);
DISPLAY INVISIBLE (-6125 3250);
FORCEPROP 1 LAST HDL_TAP TRUE
J 2
(-6450 3075);
DISPLAY 0.872340 (-6450 3075);
DISPLAY INVISIBLE (-6450 3075);
FORCEPROP 1 LAST PATH I299
J 2
(-6123 3200);
DISPLAY 0.872340 (-6123 3200);
PAINT GREEN (-6123 3200);
DISPLAY INVISIBLE (-6123 3200);
FORCEADD TAP..1
R 2
(-6125 3150);
FORCEPROP 3 LASTPIN (-6075 3150) SIG_NAME M_C_CPU0_SB_CA<5>
J 0
(-6065 3160);
DISPLAY 0.659574 (-6065 3160);
PAINT MONO (-6065 3160);
DISPLAY INVISIBLE (-6065 3160);
FORCEPROP 1 LASTPIN (-6075 3150) BN 5
J 2
(-6063 3158);
DISPLAY 0.489362 (-6063 3158);
PAINT GREEN (-6063 3158);
FORCEPROP 2 LAST CDS_LIB mstr_standard
J 0
(-6125 3150);
DISPLAY 0.723404 (-6125 3150);
PAINT MONO (-6125 3150);
DISPLAY INVISIBLE (-6125 3150);
FORCEPROP 1 LAST BODY_TYPE PLUMBING
J 2
(-6125 3200);
DISPLAY 0.872340 (-6125 3200);
PAINT GREEN (-6125 3200);
DISPLAY INVISIBLE (-6125 3200);
FORCEPROP 1 LAST HDL_TAP TRUE
J 2
(-6450 3025);
DISPLAY 0.872340 (-6450 3025);
DISPLAY INVISIBLE (-6450 3025);
FORCEPROP 1 LAST PATH I300
J 2
(-6123 3150);
DISPLAY 0.872340 (-6123 3150);
PAINT GREEN (-6123 3150);
DISPLAY INVISIBLE (-6123 3150);
FORCEADD TAP..1
R 2
(-6125 3100);
FORCEPROP 3 LASTPIN (-6075 3100) SIG_NAME M_C_CPU0_SB_CA<6>
J 0
(-6065 3110);
DISPLAY 0.659574 (-6065 3110);
PAINT MONO (-6065 3110);
DISPLAY INVISIBLE (-6065 3110);
FORCEPROP 1 LASTPIN (-6075 3100) BN 6
J 2
(-6063 3108);
DISPLAY 0.489362 (-6063 3108);
PAINT GREEN (-6063 3108);
FORCEPROP 2 LAST CDS_LIB mstr_standard
J 0
(-6125 3100);
DISPLAY 0.723404 (-6125 3100);
PAINT MONO (-6125 3100);
DISPLAY INVISIBLE (-6125 3100);
FORCEPROP 1 LAST BODY_TYPE PLUMBING
J 2
(-6125 3150);
DISPLAY 0.872340 (-6125 3150);
PAINT GREEN (-6125 3150);
DISPLAY INVISIBLE (-6125 3150);
FORCEPROP 1 LAST HDL_TAP TRUE
J 2
(-6450 2975);
DISPLAY 0.872340 (-6450 2975);
DISPLAY INVISIBLE (-6450 2975);
FORCEPROP 1 LAST PATH I301
J 2
(-6123 3100);
DISPLAY 0.872340 (-6123 3100);
PAINT GREEN (-6123 3100);
DISPLAY INVISIBLE (-6123 3100);
FORCEADD OFFPAGE..2
R 2
(-6725 3825);
FORCEPROP 2 LAST $XR0 87 
J 0
(-6979 3825);
DISPLAY 0.638298 (-6979 3825);
PAINT MONO (-6979 3825);
FORCEPROP 2 LAST PATH I302
J 0
(-7000 3875);
DISPLAY 1.021277 (-7000 3875);
DISPLAY INVISIBLE (-7000 3875);
FORCEPROP 1 LAST COMMENT_BODY TRUE
J 2
(-6680 3730);
DISPLAY 0.872340 (-6680 3730);
PAINT GREEN (-6680 3730);
DISPLAY INVISIBLE (-6680 3730);
FORCEPROP 1 LAST OFFPAGE TRUE
J 2
(-7050 3700);
DISPLAY 0.872340 (-7050 3700);
PAINT GREEN (-7050 3700);
DISPLAY INVISIBLE (-7050 3700);
FORCEPROP 2 LAST CDS_LIB standard
J 0
(-6725 3825);
DISPLAY INVISIBLE (-6725 3825);
FORCEADD OFFPAGE..2
R 2
(-6725 3425);
FORCEPROP 2 LAST $XR0 87 
J 0
(-6979 3425);
DISPLAY 0.638298 (-6979 3425);
PAINT MONO (-6979 3425);
FORCEPROP 2 LAST PATH I303
J 0
(-7000 3475);
DISPLAY 1.021277 (-7000 3475);
DISPLAY INVISIBLE (-7000 3475);
FORCEPROP 1 LAST COMMENT_BODY TRUE
J 2
(-6680 3330);
DISPLAY 0.872340 (-6680 3330);
PAINT GREEN (-6680 3330);
DISPLAY INVISIBLE (-6680 3330);
FORCEPROP 1 LAST OFFPAGE TRUE
J 2
(-7050 3300);
DISPLAY 0.872340 (-7050 3300);
PAINT GREEN (-7050 3300);
DISPLAY INVISIBLE (-7050 3300);
FORCEPROP 2 LAST CDS_LIB standard
J 0
(-6725 3425);
DISPLAY INVISIBLE (-6725 3425);
FORCEADD OFFPAGE..2
R 2
(-6725 2950);
FORCEPROP 2 LAST $XR0 87 
J 0
(-6979 2950);
DISPLAY 0.638298 (-6979 2950);
PAINT MONO (-6979 2950);
FORCEPROP 2 LAST PATH I304
J 0
(-7000 3000);
DISPLAY 1.021277 (-7000 3000);
DISPLAY INVISIBLE (-7000 3000);
FORCEPROP 1 LAST COMMENT_BODY TRUE
J 2
(-6680 2855);
DISPLAY 0.872340 (-6680 2855);
PAINT GREEN (-6680 2855);
DISPLAY INVISIBLE (-6680 2855);
FORCEPROP 1 LAST OFFPAGE TRUE
J 2
(-7050 2825);
DISPLAY 0.872340 (-7050 2825);
PAINT GREEN (-7050 2825);
DISPLAY INVISIBLE (-7050 2825);
FORCEPROP 2 LAST CDS_LIB standard
J 0
(-6725 2950);
DISPLAY INVISIBLE (-6725 2950);
FORCEADD OFFPAGE..2
R 2
(-6725 2900);
FORCEPROP 2 LAST $XR0 87 
J 0
(-6979 2900);
DISPLAY 0.638298 (-6979 2900);
PAINT MONO (-6979 2900);
FORCEPROP 2 LAST PATH I305
J 0
(-7000 2950);
DISPLAY 1.021277 (-7000 2950);
DISPLAY INVISIBLE (-7000 2950);
FORCEPROP 1 LAST COMMENT_BODY TRUE
J 2
(-6680 2805);
DISPLAY 0.872340 (-6680 2805);
PAINT GREEN (-6680 2805);
DISPLAY INVISIBLE (-6680 2805);
FORCEPROP 1 LAST OFFPAGE TRUE
J 2
(-7050 2775);
DISPLAY 0.872340 (-7050 2775);
PAINT GREEN (-7050 2775);
DISPLAY INVISIBLE (-7050 2775);
FORCEPROP 2 LAST CDS_LIB standard
J 0
(-6725 2900);
DISPLAY INVISIBLE (-6725 2900);
FORCEADD OFFPAGE..1
(-6725 2650);
FORCEPROP 2 LAST $XR0 87 
J 0
(-6946 2650);
DISPLAY 0.638298 (-6946 2650);
PAINT MONO (-6946 2650);
FORCEPROP 2 LAST PATH I306
J 0
(-6975 2700);
DISPLAY 1.021277 (-6975 2700);
DISPLAY INVISIBLE (-6975 2700);
FORCEPROP 1 LAST COMMENT_BODY TRUE
J 0
(-6600 2550);
DISPLAY 0.872340 (-6600 2550);
PAINT GREEN (-6600 2550);
DISPLAY INVISIBLE (-6600 2550);
FORCEPROP 1 LAST OFFPAGE TRUE
J 0
(-6400 2525);
DISPLAY 0.872340 (-6400 2525);
PAINT GREEN (-6400 2525);
DISPLAY INVISIBLE (-6400 2525);
FORCEPROP 2 LAST CDS_LIB standard
J 0
(-6725 2650);
DISPLAY INVISIBLE (-6725 2650);
FORCEADD OFFPAGE..2
R 2
(-6725 2800);
FORCEPROP 2 LAST $XR0 87 
J 0
(-6979 2800);
DISPLAY 0.638298 (-6979 2800);
PAINT MONO (-6979 2800);
FORCEPROP 2 LAST PATH I307
J 0
(-7000 2850);
DISPLAY 1.021277 (-7000 2850);
DISPLAY INVISIBLE (-7000 2850);
FORCEPROP 1 LAST COMMENT_BODY TRUE
J 2
(-6680 2705);
DISPLAY 0.872340 (-6680 2705);
PAINT GREEN (-6680 2705);
DISPLAY INVISIBLE (-6680 2705);
FORCEPROP 1 LAST OFFPAGE TRUE
J 2
(-7050 2675);
DISPLAY 0.872340 (-7050 2675);
PAINT GREEN (-7050 2675);
DISPLAY INVISIBLE (-7050 2675);
FORCEPROP 2 LAST CDS_LIB standard
J 0
(-6725 2800);
DISPLAY INVISIBLE (-6725 2800);
FORCEADD OFFPAGE..2
R 2
(-6725 2750);
FORCEPROP 2 LAST $XR0 87 
J 0
(-6979 2750);
DISPLAY 0.638298 (-6979 2750);
PAINT MONO (-6979 2750);
FORCEPROP 2 LAST PATH I308
J 0
(-7000 2800);
DISPLAY 1.021277 (-7000 2800);
DISPLAY INVISIBLE (-7000 2800);
FORCEPROP 1 LAST COMMENT_BODY TRUE
J 2
(-6680 2655);
DISPLAY 0.872340 (-6680 2655);
PAINT GREEN (-6680 2655);
DISPLAY INVISIBLE (-6680 2655);
FORCEPROP 1 LAST OFFPAGE TRUE
J 2
(-7050 2625);
DISPLAY 0.872340 (-7050 2625);
PAINT GREEN (-7050 2625);
DISPLAY INVISIBLE (-7050 2625);
FORCEPROP 2 LAST CDS_LIB standard
J 0
(-6725 2750);
DISPLAY INVISIBLE (-6725 2750);
FORCEADD OFFPAGE..5
(-6725 2550);
FORCEPROP 2 LAST $XR0 87 
J 0
(-6979 2550);
DISPLAY 0.638298 (-6979 2550);
PAINT MONO (-6979 2550);
FORCEPROP 2 LAST PATH I309
J 0
(-7000 2600);
DISPLAY 1.021277 (-7000 2600);
DISPLAY INVISIBLE (-7000 2600);
FORCEPROP 1 LAST COMMENT_BODY TRUE
J 0
(-6625 2475);
DISPLAY 0.872340 (-6625 2475);
PAINT GREEN (-6625 2475);
DISPLAY INVISIBLE (-6625 2475);
FORCEPROP 1 LAST OFFPAGE TRUE
J 0
(-6400 2425);
DISPLAY 0.872340 (-6400 2425);
PAINT GREEN (-6400 2425);
DISPLAY INVISIBLE (-6400 2425);
FORCEPROP 2 LAST CDS_LIB mstr_standard
J 0
(-6725 2550);
DISPLAY INVISIBLE (-6725 2550);
FORCEADD OFFPAGE..2
R 2
(-6725 2450);
FORCEPROP 2 LAST $XR0 87 
J 0
(-6979 2450);
DISPLAY 0.638298 (-6979 2450);
PAINT MONO (-6979 2450);
FORCEPROP 2 LAST PATH I310
J 0
(-7000 2500);
DISPLAY 1.021277 (-7000 2500);
DISPLAY INVISIBLE (-7000 2500);
FORCEPROP 1 LAST COMMENT_BODY TRUE
J 2
(-6680 2355);
DISPLAY 0.872340 (-6680 2355);
PAINT GREEN (-6680 2355);
DISPLAY INVISIBLE (-6680 2355);
FORCEPROP 1 LAST OFFPAGE TRUE
J 2
(-7050 2325);
DISPLAY 0.872340 (-7050 2325);
PAINT GREEN (-7050 2325);
DISPLAY INVISIBLE (-7050 2325);
FORCEPROP 2 LAST CDS_LIB standard
J 0
(-6725 2450);
DISPLAY INVISIBLE (-6725 2450);
FORCEADD OFFPAGE..2
R 2
(-6725 2400);
FORCEPROP 2 LAST $XR0 87 
J 0
(-6979 2400);
DISPLAY 0.638298 (-6979 2400);
PAINT MONO (-6979 2400);
FORCEPROP 2 LAST PATH I311
J 0
(-7000 2450);
DISPLAY 1.021277 (-7000 2450);
DISPLAY INVISIBLE (-7000 2450);
FORCEPROP 1 LAST COMMENT_BODY TRUE
J 2
(-6680 2305);
DISPLAY 0.872340 (-6680 2305);
PAINT GREEN (-6680 2305);
DISPLAY INVISIBLE (-6680 2305);
FORCEPROP 1 LAST OFFPAGE TRUE
J 2
(-7050 2275);
DISPLAY 0.872340 (-7050 2275);
PAINT GREEN (-7050 2275);
DISPLAY INVISIBLE (-7050 2275);
FORCEPROP 2 LAST CDS_LIB standard
J 0
(-6725 2400);
DISPLAY INVISIBLE (-6725 2400);
FORCEADD OFFPAGE..1
(-6725 2300);
FORCEPROP 2 LAST $XR0 87 
J 0
(-6946 2300);
DISPLAY 0.638298 (-6946 2300);
PAINT MONO (-6946 2300);
FORCEPROP 2 LAST PATH I312
J 0
(-6975 2350);
DISPLAY 1.021277 (-6975 2350);
DISPLAY INVISIBLE (-6975 2350);
FORCEPROP 1 LAST COMMENT_BODY TRUE
J 0
(-6600 2200);
DISPLAY 0.872340 (-6600 2200);
PAINT GREEN (-6600 2200);
DISPLAY INVISIBLE (-6600 2200);
FORCEPROP 1 LAST OFFPAGE TRUE
J 0
(-6400 2175);
DISPLAY 0.872340 (-6400 2175);
PAINT GREEN (-6400 2175);
DISPLAY INVISIBLE (-6400 2175);
FORCEPROP 2 LAST CDS_LIB standard
J 0
(-6725 2300);
DISPLAY INVISIBLE (-6725 2300);
FORCEADD OFFPAGE..5
(-6725 2200);
FORCEPROP 2 LAST $XR0 87 
J 0
(-6979 2200);
DISPLAY 0.638298 (-6979 2200);
PAINT MONO (-6979 2200);
FORCEPROP 2 LAST PATH I313
J 0
(-7000 2250);
DISPLAY 1.021277 (-7000 2250);
DISPLAY INVISIBLE (-7000 2250);
FORCEPROP 1 LAST COMMENT_BODY TRUE
J 0
(-6625 2125);
DISPLAY 0.872340 (-6625 2125);
PAINT GREEN (-6625 2125);
DISPLAY INVISIBLE (-6625 2125);
FORCEPROP 1 LAST OFFPAGE TRUE
J 0
(-6400 2075);
DISPLAY 0.872340 (-6400 2075);
PAINT GREEN (-6400 2075);
DISPLAY INVISIBLE (-6400 2075);
FORCEPROP 2 LAST CDS_LIB standard
J 0
(-6725 2200);
DISPLAY INVISIBLE (-6725 2200);
FORCEADD Q_RES..1
(-7050 2100);
FORCEPROP 1 LAST LOCATION R377
J 0
(-7375 2100);
DISPLAY 0.489362 (-7375 2100);
PAINT SKYBLUE (-7375 2100);
FORCEPROP 0 LAST $SEC 1
J 0
(-7225 2150);
DISPLAY 0.680851 (-7225 2150);
PAINT MONO (-7225 2150);
DISPLAY INVISIBLE (-7225 2150);
FORCEPROP 0 LAST CDS_SEC 1
J 0
(-7225 2150);
DISPLAY 1.021277 (-7225 2150);
DISPLAY INVISIBLE (-7225 2150);
FORCEPROP 1 LASTPIN (-7150 2100) $PN 1
J 0
(-7138 2112);
DISPLAY 0.489362 (-7138 2112);
PAINT MONO (-7138 2112);
FORCEPROP 1 LASTPIN (-6950 2100) $PN 2
J 0
(-6988 2112);
DISPLAY 0.489362 (-6988 2112);
PAINT MONO (-6988 2112);
FORCEPROP 1 LAST TOLERANCE 1%
J 0
(-6775 2100);
DISPLAY 0.489362 (-6775 2100);
PAINT SKYBLUE (-6775 2100);
FORCEPROP 1 LAST VALUE 15   
J 2
(-6725 2100);
DISPLAY 0.489362 (-6725 2100);
PAINT SKYBLUE (-6725 2100);
FORCEPROP 1 LAST PART_NUMBER CS01502FB11
J 0
(-6925 2075);
DISPLAY 0.489362 (-6925 2075);
PAINT SKYBLUE (-6925 2075);
FORCEPROP 1 LAST PACK_TYPE 0402LF
J 0
(-7375 2075);
DISPLAY 0.489362 (-7375 2075);
PAINT SKYBLUE (-7375 2075);
FORCEPROP 2 LAST CDS_LIB pure_quanta
J 0
(-7050 2100);
DISPLAY INVISIBLE (-7050 2100);
FORCEPROP 1 LAST PATH I314
J 0
(-7100 2250);
DISPLAY 0.978723 (-7100 2250);
PAINT WHITE (-7100 2250);
DISPLAY INVISIBLE (-7100 2250);
FORCEPROP 1 LAST WATTAGE 1/16W
J 2
(-6825 2225);
DISPLAY 0.638298 (-6825 2225);
PAINT SKYBLUE (-6825 2225);
DISPLAY INVISIBLE (-6825 2225);
FORCEPROP 1 LAST MATERIAL CHIP
J 0
(-7175 2225);
DISPLAY 0.638298 (-7175 2225);
PAINT SKYBLUE (-7175 2225);
DISPLAY INVISIBLE (-7175 2225);
FORCEADD OFFPAGE..1
(-7925 2100);
FORCEPROP 2 LAST $XR0 87 
J 0
(-8176 2100);
DISPLAY 0.638298 (-8176 2100);
PAINT MONO (-8176 2100);
FORCEPROP 2 LAST PATH I315
J 0
(-8200 2150);
DISPLAY 1.021277 (-8200 2150);
DISPLAY INVISIBLE (-8200 2150);
FORCEPROP 1 LAST COMMENT_BODY TRUE
J 0
(-7800 2000);
DISPLAY 0.872340 (-7800 2000);
PAINT GREEN (-7800 2000);
DISPLAY INVISIBLE (-7800 2000);
FORCEPROP 1 LAST OFFPAGE TRUE
J 0
(-7600 1975);
DISPLAY 0.872340 (-7600 1975);
PAINT GREEN (-7600 1975);
DISPLAY INVISIBLE (-7600 1975);
FORCEPROP 2 LAST CDS_LIB mstr_standard
J 0
(-7925 2100);
DISPLAY INVISIBLE (-7925 2100);
FORCEADD OFFPAGE..5
(-6725 2000);
FORCEPROP 2 LAST $XR0 87 
J 0
(-6979 2000);
DISPLAY 0.638298 (-6979 2000);
PAINT MONO (-6979 2000);
FORCEPROP 2 LAST PATH I316
J 0
(-7000 2050);
DISPLAY 1.021277 (-7000 2050);
DISPLAY INVISIBLE (-7000 2050);
FORCEPROP 1 LAST COMMENT_BODY TRUE
J 0
(-6625 1925);
DISPLAY 0.872340 (-6625 1925);
PAINT GREEN (-6625 1925);
DISPLAY INVISIBLE (-6625 1925);
FORCEPROP 1 LAST OFFPAGE TRUE
J 0
(-6400 1875);
DISPLAY 0.872340 (-6400 1875);
PAINT GREEN (-6400 1875);
DISPLAY INVISIBLE (-6400 1875);
FORCEPROP 2 LAST CDS_LIB standard
J 0
(-6725 2000);
DISPLAY INVISIBLE (-6725 2000);
FORCEADD QUANTA_TITLE_BLOCK_C..1
(-100 100);
FORCEPROP 0 LAST CDS_CON_LAST_MODIFIED Fri Mar 11 14:52:11 2022
J 0
(-1985 115);
DISPLAY INVISIBLE (-1985 115);
FORCEPROP 1 LAST CUSTOM_TXT_CDS <CON_LAST_MODIFIED>
J 0
(-1985 115);
DISPLAY 0.978723 (-1985 115);
FORCEPROP 2 LAST CUSTOM_TXT_CDS <XR_PAGE_TITLE>
J 0
(-7990 5350);
DISPLAY 0.638298 (-7990 5350);
PAINT PINK (-7990 5350);
DISPLAY INVISIBLE (-7990 5350);
FORCEPROP 1 LAST CUSTOM_TXT_CDS <NAME_2>
J 0
(-3275 150);
FORCEPROP 1 LAST CUSTOM_TXT_CDS <NAME_1>
J 0
(-3275 275);
FORCEPROP 1 LAST CUSTOM_TXT_CDS <Q_NUMBER>
J 0
(-1503 203);
DISPLAY 1.212766 (-1503 203);
FORCEPROP 1 LAST CUSTOM_TXT_CDS <Q_PROJ>
J 0
(-2482 202);
DISPLAY 1.212766 (-2482 202);
FORCEPROP 1 LAST CUSTOM_TXT_CDS <Q_REV>
J 0
(-284 203);
DISPLAY 1.212766 (-284 203);
FORCEPROP 1 LAST CUSTOM_TXT_CDS <CON_PAGE_NUM> OF <CON_TOTAL_PAGES>
J 0
(-546 118);
DISPLAY 0.978723 (-546 118);
FORCEPROP 1 LAST Q_TITLE CPU0 DDR CHC
J 0
(-9400 150);
DISPLAY 2.446809 (-9400 150);
PAINT GREEN (-9400 150);
FORCEPROP 1 LAST Q_DEPT BU9
J 1
(-3863 149);
DISPLAY 1.957447 (-3863 149);
PAINT GREEN (-3863 149);
FORCEPROP 1 LAST CDS_LMAN_SYM_OUTLINE -9475,6775,100,-125
J 0
(-100 100);
DISPLAY 0.468085 (-100 100);
PAINT GREEN (-100 100);
DISPLAY INVISIBLE (-100 100);
FORCEPROP 2 LAST CDS_LIB pure_quanta
J 0
(-100 100);
DISPLAY INVISIBLE (-100 100);
FORCEPROP 2 LAST PAGE_BORDER TRUE
J 0
(-7990 5350);
DISPLAY 0.638298 (-7990 5350);
PAINT PINK (-7990 5350);
DISPLAY INVISIBLE (-7990 5350);
FORCEPROP 1 LAST COMMENT_BODY TRUE
J 0
(-88 87);
DISPLAY 0.978723 (-88 87);
PAINT GREEN (-88 87);
DISPLAY INVISIBLE (-88 87);
FORCEPROP 2 LAST CDS_XR_PAGE_TITLE CR-12 : @T6G_MB_LIB.T6G(SCH_1):PAGE12
J 0
(-7990 5350);
DISPLAY 0.638298 (-7990 5350);
PAINT PINK (-7990 5350);
DISPLAY INVISIBLE (-7990 5350);
FORCEADD CAD_NOTE..1
(-7825 2375);
FORCEPROP 0 LAST L1 R1951 PLACE CLOSE TO CPU < 25MM
J 0
(-7975 2250);
DISPLAY 0.617021 (-7975 2250);
PAINT WHITE (-7975 2250);
FORCEPROP 2 LAST CDS_LIB pure_quanta_power
J 0
(-7825 2375);
DISPLAY INVISIBLE (-7825 2375);
FORCEPROP 1 LAST COMMENT_BODY TRUE
J 0
(-7800 2475);
DISPLAY 0.574468 (-7800 2475);
PAINT WHITE (-7800 2475);
DISPLAY INVISIBLE (-7800 2475);
WIRE 17 -1 (-3450 5225)(-3450 5175);
WIRE 17 -1 (-3450 5275)(-3450 5225);
WIRE 17 -1 (-3450 5075)(-3450 5175);
WIRE 17 -1 (-3450 5025)(-3450 5075);
WIRE 17 -1 (-3450 5325)(-3450 5275);
WIRE 17 -1 (-3450 5375)(-3450 5325);
WIRE 17 -1 (-3450 4975)(-3450 5025);
WIRE 17 -1 (-3450 4925)(-3450 4975);
WIRE 17 -1 (-3450 5425)(-3450 5375);
WIRE 17 -1 (-3450 5475)(-3450 5425);
WIRE 17 -1 (-3450 4925)(-3450 4875);
WIRE 17 -1 (-3450 4875)(-3450 4825);
WIRE 17 -1 (-3450 5525)(-3450 5475);
WIRE 17 -1 (-3450 5625)(-3450 5525);
WIRE 17 -1 (-3450 4825)(-3450 4775);
WIRE 17 -1 (-3450 4775)(-3450 4725);
WIRE 17 -1 (-3450 5675)(-3450 5625);
WIRE 17 -1 (-3450 5725)(-3450 5675);
WIRE 17 -1 (-3450 4725)(-3450 4625);
WIRE 17 -1 (-3450 4625)(-3450 4575);
WIRE 17 -1 (-3450 5775)(-3450 5725);
WIRE 17 -1 (-3450 5825)(-3450 5775);
WIRE 17 -1 (-3450 4575)(-3450 4525);
WIRE 17 -1 (-3450 4525)(-3450 4475);
WIRE 17 -1 (-3450 5875)(-3450 5825);
WIRE 17 -1 (-3450 5925)(-3450 5875);
WIRE 17 -1 (-3450 4425)(-3450 4475);
WIRE 17 -1 (-3450 4375)(-3450 4425);
WIRE 17 -1 (-3450 5975)(-3450 5925);
WIRE 17 -1 (-3450 5975)(-2825 5975);
FORCEPROP 2 LAST SIG_NAME M_C_CPU0_SA_DQ<31:0>
J 2
(-2885 5985);
DISPLAY 0.489362 (-2885 5985);
WIRE 17 -1 (-3450 4325)(-3450 4375);
WIRE 17 -1 (-3450 4275)(-3450 4325);
WIRE 17 -1 (-3450 4175)(-3450 4125);
WIRE 17 -1 (-3450 4175)(-2825 4175);
FORCEPROP 2 LAST SIG_NAME M_C_CPU0_SB_DQ<31:0>
J 2
(-2885 4185);
DISPLAY 0.489362 (-2885 4185);
WIRE 17 -1 (-3450 3725)(-3450 3675);
WIRE 17 -1 (-3450 3825)(-3450 3725);
WIRE 17 -1 (-3450 3675)(-3450 3625);
WIRE 17 -1 (-3450 3625)(-3450 3575);
WIRE 17 -1 (-3450 3875)(-3450 3825);
WIRE 17 -1 (-3450 3925)(-3450 3875);
WIRE 17 -1 (-3450 3575)(-3450 3525);
WIRE 17 -1 (-3450 3525)(-3450 3475);
WIRE 17 -1 (-3450 3975)(-3450 3925);
WIRE 17 -1 (-3450 4025)(-3450 3975);
WIRE 17 -1 (-3450 3475)(-3450 3425);
WIRE 17 -1 (-3450 3425)(-3450 3375);
WIRE 17 -1 (-3450 4075)(-3450 4025);
WIRE 17 -1 (-3450 4125)(-3450 4075);
WIRE 17 -1 (-3450 3275)(-3450 3375);
WIRE 17 -1 (-3450 3225)(-3450 3275);
WIRE 17 -1 (-3450 3175)(-3450 3225);
WIRE 17 -1 (-3450 3125)(-3450 3175);
WIRE 17 -1 (-3450 3125)(-3450 3075);
WIRE 17 -1 (-3450 3075)(-3450 3025);
WIRE 17 -1 (-3450 3025)(-3450 2975);
WIRE 17 -1 (-3450 2975)(-3450 2925);
WIRE 17 -1 (-3450 2925)(-3450 2825);
WIRE 17 -1 (-3450 2825)(-3450 2775);
WIRE 17 -1 (-3450 2775)(-3450 2725);
WIRE 17 -1 (-3450 2725)(-3450 2675);
WIRE 17 -1 (-3450 2625)(-3450 2675);
WIRE 17 -1 (-3450 2575)(-3450 2625);
WIRE 17 -1 (-3450 2525)(-3450 2575);
WIRE 17 -1 (-3450 2475)(-3450 2525);
WIRE 17 -1 (-3450 2125)(-3450 2175);
WIRE 17 -1 (-3450 2075)(-3450 2125);
WIRE 17 -1 (-3450 2175)(-3450 2225);
WIRE 17 -1 (-3450 2275)(-3450 2225);
WIRE 17 -1 (-3450 2025)(-3450 2075);
WIRE 17 -1 (-3450 2275)(-3450 2325);
WIRE 17 -1 (-3450 2375)(-3450 2325);
WIRE 17 -1 (-3450 2375)(-3450 2400);
WIRE 17 -1 (-3450 2400)(-2950 2400);
FORCEPROP 2 LAST SIG_NAME M_C_CPU0_SA_CB<7:0>
J 2
(-2950 2410);
DISPLAY 0.489362 (-2950 2410);
WIRE 17 -1 (-3450 1925)(-3450 1950);
WIRE 17 -1 (-3450 1925)(-3450 1875);
WIRE 17 -1 (-3450 1950)(-2950 1950);
FORCEPROP 2 LAST SIG_NAME M_C_CPU0_SB_CB<7:0>
J 2
(-2950 1960);
DISPLAY 0.489362 (-2950 1960);
WIRE 17 -1 (-3450 1825)(-3450 1875);
WIRE 17 -1 (-3450 1825)(-3450 1775);
WIRE 17 -1 (-3450 1725)(-3450 1775);
WIRE 17 -1 (-3450 1675)(-3450 1725);
WIRE 17 -1 (-3450 1625)(-3450 1675);
WIRE 17 -1 (-3450 1575)(-3450 1625);
WIRE 17 -1 (-6175 5925)(-6175 5825);
FORCEPROP 2 LAST SIG_NAME M_C_CPU0_SA_DQS_DN<9:0>
J 2
(-6210 5935);
DISPLAY 0.489362 (-6210 5935);
WIRE 17 -1 (-6175 5725)(-6175 5625);
WIRE 17 -1 (-6175 5825)(-6175 5725);
WIRE 17 -1 (-6175 5625)(-6175 5525);
WIRE 17 -1 (-6175 5425)(-6175 5525);
WIRE 17 -1 (-6175 5325)(-6175 5425);
WIRE 17 -1 (-6175 5225)(-6175 5325);
WIRE 17 -1 (-6175 5225)(-6175 5125);
WIRE 17 -1 (-5975 5975)(-5975 5875);
WIRE 17 -1 (-5975 5975)(-6775 5975);
FORCEPROP 2 LAST SIG_NAME M_C_CPU0_SA_DQS_DP<9:0>
J 2
(-6210 5985);
DISPLAY 0.489362 (-6210 5985);
WIRE 17 -1 (-6175 5125)(-6175 5025);
WIRE 17 -1 (-5975 5875)(-5975 5775);
WIRE 17 -1 (-5975 5775)(-5975 5675);
WIRE 17 -1 (-5975 5675)(-5975 5575);
WIRE 17 -1 (-5975 5475)(-5975 5575);
WIRE 17 -1 (-5975 5375)(-5975 5475);
WIRE 17 -1 (-5975 5275)(-5975 5375);
WIRE 17 -1 (-5975 5275)(-5975 5175);
WIRE 17 -1 (-5975 5175)(-5975 5075);
WIRE 17 -1 (-5975 4225)(-5975 4125);
WIRE 17 -1 (-5975 4225)(-5975 4325);
WIRE 17 -1 (-5975 4125)(-5975 4025);
WIRE 17 -1 (-5975 4325)(-5975 4425);
WIRE 17 -1 (-5975 4425)(-5975 4525);
WIRE 17 -1 (-5975 4625)(-5975 4525);
WIRE 17 -1 (-5975 4725)(-5975 4625);
WIRE 17 -1 (-5975 4825)(-5975 4725);
WIRE 17 -1 (-5975 4925)(-5975 4825);
WIRE 17 -1 (-5975 4925)(-6775 4925);
FORCEPROP 2 LAST SIG_NAME M_C_CPU0_SB_DQS_DP<9:0>
J 2
(-6210 4935);
DISPLAY 0.489362 (-6210 4935);
WIRE 17 -1 (-6175 4875)(-6175 4775);
FORCEPROP 2 LAST SIG_NAME M_C_CPU0_SB_DQS_DN<9:0>
J 2
(-6210 4885);
DISPLAY 0.489362 (-6210 4885);
WIRE 17 -1 (-6175 4675)(-6175 4575);
WIRE 17 -1 (-6175 4775)(-6175 4675);
WIRE 17 -1 (-6175 4575)(-6175 4475);
WIRE 17 -1 (-6175 4375)(-6175 4475);
WIRE 17 -1 (-6175 4275)(-6175 4375);
WIRE 17 -1 (-6175 4175)(-6175 4275);
WIRE 17 -1 (-6175 4175)(-6175 4075);
WIRE 17 -1 (-6175 4075)(-6175 3975);
WIRE 17 -1 (-6175 3775)(-6175 3825);
WIRE 17 -1 (-6175 3725)(-6175 3775);
WIRE 17 -1 (-6175 3825)(-6675 3825);
FORCEPROP 2 LAST SIG_NAME M_C_CPU0_SA_CA<6:0>
J 0
(-6675 3835);
DISPLAY 0.489362 (-6675 3835);
WIRE 17 -1 (-6175 3375)(-6175 3425);
WIRE 17 -1 (-6175 3325)(-6175 3375);
WIRE 17 -1 (-6175 3425)(-6675 3425);
FORCEPROP 2 LAST SIG_NAME M_C_CPU0_SB_CA<6:0>
J 0
(-6675 3435);
DISPLAY 0.489362 (-6675 3435);
WIRE 17 -1 (-6175 3675)(-6175 3725);
WIRE 17 -1 (-6175 3275)(-6175 3325);
WIRE 17 -1 (-6175 3625)(-6175 3675);
WIRE 17 -1 (-6175 3575)(-6175 3625);
WIRE 17 -1 (-6175 3525)(-6175 3575);
WIRE 17 -1 (-6175 3225)(-6175 3275);
WIRE 17 -1 (-6175 3175)(-6175 3225);
WIRE 17 -1 (-6175 3125)(-6175 3175);
WIRE 17 -1 (-6175 5925)(-6775 5925);
WIRE 17 -1 (-6175 4875)(-6775 4875);
WIRE 16 -1 (-7875 2100)(-7150 2100);
FORCEPROP 2 LAST SIG_NAME M_C_CPU0_ALERT_N
J 0
(-7835 2110);
DISPLAY 0.489362 (-7835 2110);
WIRE 16 -1 (-6675 1150)(-5575 1150);
FORCEPROP 2 LAST SIG_NAME TP_M_C_CPU0_SA_TEST39C
J 0
(-6660 1160);
DISPLAY 0.489362 (-6660 1160);
FORCEPROP 2 LASTPROP $XRERR UNIQUE?
J 0
(-6915 1150);
DISPLAY 0.638298 (-6915 1150);
PAINT MONO (-6915 1150);
DISPLAY INVISIBLE (-6915 1150);
WIRE 16 -1 (-6950 2100)(-5575 2100);
FORCEPROP 2 LAST SIG_NAME M_C_CPU0_ALERT_R_N
J 0
(-6660 2110);
DISPLAY 0.489362 (-6660 2110);
FORCEPROP 2 LASTPROP $XRERR UNIQUE?
J 0
(-6900 2110);
DISPLAY 0.638298 (-6900 2110);
PAINT MONO (-6900 2110);
DISPLAY INVISIBLE (-6900 2110);
WIRE 16 -1 (-6675 2950)(-5575 2950);
FORCEPROP 2 LAST SIG_NAME M_C_CPU0_CLK_DP<0>
J 0
(-6675 2960);
DISPLAY 0.489362 (-6675 2960);
WIRE 16 -1 (-6675 2900)(-5575 2900);
FORCEPROP 2 LAST SIG_NAME M_C_CPU0_CLK_DN<0>
J 0
(-6675 2910);
DISPLAY 0.489362 (-6675 2910);
WIRE 16 -1 (-6675 2650)(-5575 2650);
FORCEPROP 2 LAST SIG_NAME M_C_CPU0_SA_RSP<0>
J 0
(-6675 2660);
DISPLAY 0.489362 (-6675 2660);
WIRE 16 -1 (-6675 2800)(-5575 2800);
FORCEPROP 2 LAST SIG_NAME M_C_CPU0_SA_CS_N<0>
J 0
(-6675 2810);
DISPLAY 0.489362 (-6675 2810);
WIRE 16 -1 (-6675 2750)(-5575 2750);
FORCEPROP 2 LAST SIG_NAME M_C_CPU0_SA_CS_N<1>
J 0
(-6675 2760);
DISPLAY 0.489362 (-6675 2760);
WIRE 16 -1 (-6675 2550)(-5575 2550);
FORCEPROP 2 LAST SIG_NAME M_C_CPU0_SA_PAR
J 0
(-6675 2560);
DISPLAY 0.489362 (-6675 2560);
WIRE 16 -1 (-6675 2450)(-5575 2450);
FORCEPROP 2 LAST SIG_NAME M_C_CPU0_SB_CS_N<0>
J 0
(-6675 2460);
DISPLAY 0.489362 (-6675 2460);
WIRE 16 -1 (-6675 2400)(-5575 2400);
FORCEPROP 2 LAST SIG_NAME M_C_CPU0_SB_CS_N<1>
J 0
(-6675 2410);
DISPLAY 0.489362 (-6675 2410);
WIRE 16 -1 (-6675 2300)(-5575 2300);
FORCEPROP 2 LAST SIG_NAME M_C_CPU0_SB_RSP<0>
J 0
(-6675 2310);
DISPLAY 0.489362 (-6675 2310);
WIRE 16 -1 (-6675 2200)(-5575 2200);
FORCEPROP 2 LAST SIG_NAME M_C_CPU0_SB_PAR
J 0
(-6675 2210);
DISPLAY 0.489362 (-6675 2210);
WIRE 16 -1 (-6675 2000)(-5575 2000);
FORCEPROP 2 LAST SIG_NAME M_C_CPU0_RESET_N
J 0
(-6675 2010);
DISPLAY 0.489362 (-6675 2010);
WIRE 16 -1 (-5875 4000)(-5575 4000);
WIRE 16 -1 (-6075 3100)(-5575 3100);
WIRE 16 -1 (-6075 3950)(-5575 3950);
WIRE 16 -1 (-6075 3500)(-5575 3500);
WIRE 16 -1 (-6075 3150)(-5575 3150);
WIRE 16 -1 (-6075 4050)(-5575 4050);
WIRE 16 -1 (-6075 3550)(-5575 3550);
WIRE 16 -1 (-6075 3200)(-5575 3200);
WIRE 16 -1 (-6075 3600)(-5575 3600);
WIRE 16 -1 (-6075 3250)(-5575 3250);
WIRE 16 -1 (-6075 3650)(-5575 3650);
WIRE 16 -1 (-6075 3300)(-5575 3300);
WIRE 16 -1 (-6075 3700)(-5575 3700);
WIRE 16 -1 (-6075 3350)(-5575 3350);
WIRE 16 -1 (-6075 3750)(-5575 3750);
WIRE 16 -1 (-6075 3400)(-5575 3400);
WIRE 16 -1 (-6075 3800)(-5575 3800);
WIRE 16 -1 (-5875 4200)(-5575 4200);
WIRE 16 -1 (-5875 4300)(-5575 4300);
WIRE 16 -1 (-5875 4400)(-5575 4400);
WIRE 16 -1 (-5875 4500)(-5575 4500);
WIRE 16 -1 (-5875 5050)(-5575 5050);
WIRE 16 -1 (-5875 4600)(-5575 4600);
WIRE 16 -1 (-6075 4150)(-5575 4150);
WIRE 16 -1 (-5875 4700)(-5575 4700);
WIRE 16 -1 (-6075 4250)(-5575 4250);
WIRE 16 -1 (-5875 4800)(-5575 4800);
WIRE 16 -1 (-6075 4350)(-5575 4350);
WIRE 16 -1 (-5875 4900)(-5575 4900);
WIRE 16 -1 (-6075 4450)(-5575 4450);
WIRE 16 -1 (-6075 5000)(-5575 5000);
WIRE 16 -1 (-6075 4550)(-5575 4550);
WIRE 16 -1 (-6075 5100)(-5575 5100);
WIRE 16 -1 (-6075 4650)(-5575 4650);
WIRE 16 -1 (-6075 4750)(-5575 4750);
WIRE 16 -1 (-6075 4850)(-5575 4850);
WIRE 16 -1 (-5875 4100)(-5575 4100);
WIRE 16 -1 (-6075 5900)(-5575 5900);
WIRE 16 -1 (-5875 5150)(-5575 5150);
WIRE 16 -1 (-5875 5250)(-5575 5250);
WIRE 16 -1 (-5875 5350)(-5575 5350);
WIRE 16 -1 (-5875 5450)(-5575 5450);
WIRE 16 -1 (-5875 5550)(-5575 5550);
WIRE 16 -1 (-5875 5650)(-5575 5650);
WIRE 16 -1 (-6075 5200)(-5575 5200);
WIRE 16 -1 (-5875 5750)(-5575 5750);
WIRE 16 -1 (-6075 5300)(-5575 5300);
WIRE 16 -1 (-5875 5850)(-5575 5850);
WIRE 16 -1 (-6075 5400)(-5575 5400);
WIRE 16 -1 (-5875 5950)(-5575 5950);
WIRE 16 -1 (-6075 5500)(-5575 5500);
WIRE 16 -1 (-6075 5600)(-5575 5600);
WIRE 16 -1 (-6075 5700)(-5575 5700);
WIRE 16 -1 (-6075 5800)(-5575 5800);
WIRE 16 -1 (-3975 1550)(-3550 1550);
WIRE 16 -1 (-3975 1600)(-3550 1600);
WIRE 16 -1 (-3975 1650)(-3550 1650);
WIRE 16 -1 (-3975 1700)(-3550 1700);
WIRE 16 -1 (-3975 1750)(-3550 1750);
WIRE 16 -1 (-3975 1800)(-3550 1800);
WIRE 16 -1 (-3975 2000)(-3550 2000);
WIRE 16 -1 (-3975 1850)(-3550 1850);
WIRE 16 -1 (-3975 1900)(-3550 1900);
WIRE 16 -1 (-3975 2150)(-3550 2150);
WIRE 16 -1 (-3975 2200)(-3550 2200);
WIRE 16 -1 (-3975 2250)(-3550 2250);
WIRE 16 -1 (-3975 2300)(-3550 2300);
WIRE 16 -1 (-3975 2350)(-3550 2350);
WIRE 16 -1 (-3975 2550)(-3550 2550);
WIRE 16 -1 (-3975 2600)(-3550 2600);
WIRE 16 -1 (-3975 2650)(-3550 2650);
WIRE 16 -1 (-3975 2700)(-3550 2700);
WIRE 16 -1 (-3975 2750)(-3550 2750);
WIRE 16 -1 (-3975 2800)(-3550 2800);
WIRE 16 -1 (-3975 2900)(-3550 2900);
WIRE 16 -1 (-3975 2950)(-3550 2950);
WIRE 16 -1 (-3975 3000)(-3550 3000);
WIRE 16 -1 (-3975 2050)(-3550 2050);
WIRE 16 -1 (-3975 3050)(-3550 3050);
WIRE 16 -1 (-3975 2450)(-3550 2450);
WIRE 16 -1 (-3975 2100)(-3550 2100);
WIRE 16 -1 (-3975 2500)(-3550 2500);
WIRE 16 -1 (-3975 3800)(-3550 3800);
WIRE 16 -1 (-3975 3850)(-3550 3850);
WIRE 16 -1 (-3975 3900)(-3550 3900);
WIRE 16 -1 (-3975 3950)(-3550 3950);
WIRE 16 -1 (-3975 4000)(-3550 4000);
WIRE 16 -1 (-3975 4050)(-3550 4050);
WIRE 16 -1 (-3975 3100)(-3550 3100);
WIRE 16 -1 (-3975 3150)(-3550 3150);
WIRE 16 -1 (-3975 3200)(-3550 3200);
WIRE 16 -1 (-3975 3250)(-3550 3250);
WIRE 16 -1 (-3975 3350)(-3550 3350);
WIRE 16 -1 (-3975 3400)(-3550 3400);
WIRE 16 -1 (-3975 3450)(-3550 3450);
WIRE 16 -1 (-3975 3500)(-3550 3500);
WIRE 16 -1 (-3975 3550)(-3550 3550);
WIRE 16 -1 (-3975 3600)(-3550 3600);
WIRE 16 -1 (-3975 3650)(-3550 3650);
WIRE 16 -1 (-3975 3700)(-3550 3700);
WIRE 16 -1 (-3975 4600)(-3550 4600);
WIRE 16 -1 (-3975 4700)(-3550 4700);
WIRE 16 -1 (-3975 4750)(-3550 4750);
WIRE 16 -1 (-3975 4800)(-3550 4800);
WIRE 16 -1 (-3975 4850)(-3550 4850);
WIRE 16 -1 (-3975 4250)(-3550 4250);
WIRE 16 -1 (-3975 4300)(-3550 4300);
WIRE 16 -1 (-3975 4100)(-3550 4100);
WIRE 16 -1 (-3975 4150)(-3550 4150);
WIRE 16 -1 (-3975 4900)(-3550 4900);
WIRE 16 -1 (-3975 4950)(-3550 4950);
WIRE 16 -1 (-3975 4350)(-3550 4350);
WIRE 16 -1 (-3975 5000)(-3550 5000);
WIRE 16 -1 (-3975 4400)(-3550 4400);
WIRE 16 -1 (-3975 5050)(-3550 5050);
WIRE 16 -1 (-3975 4450)(-3550 4450);
WIRE 16 -1 (-3975 4500)(-3550 4500);
WIRE 16 -1 (-3975 4550)(-3550 4550);
WIRE 16 -1 (-3975 5500)(-3550 5500);
WIRE 16 -1 (-3975 5250)(-3550 5250);
WIRE 16 -1 (-3975 5600)(-3550 5600);
WIRE 16 -1 (-3975 5300)(-3550 5300);
WIRE 16 -1 (-3975 5650)(-3550 5650);
WIRE 16 -1 (-3975 5350)(-3550 5350);
WIRE 16 -1 (-3975 5700)(-3550 5700);
WIRE 16 -1 (-3975 5400)(-3550 5400);
WIRE 16 -1 (-3975 5750)(-3550 5750);
WIRE 16 -1 (-3975 5800)(-3550 5800);
WIRE 16 -1 (-3975 5850)(-3550 5850);
WIRE 16 -1 (-3975 5900)(-3550 5900);
WIRE 16 -1 (-3975 5950)(-3550 5950);
WIRE 16 -1 (-3975 5150)(-3550 5150);
WIRE 16 -1 (-3975 5450)(-3550 5450);
WIRE 16 -1 (-3975 5200)(-3550 5200);
QUIT
